FILE_TYPE = MACRO_DRAWING;
SET COLOR_WIRE YELLOW;
SET COLOR_PROP ORANGE;
SET COLOR_DOT WHITE;
SET COLOR_ARC YELLOW;
SET COLOR_BODY GREEN;
SET COLOR_NOTE PURPLE;
SET PROP_DISPLAY VALUE;
SET PAGE_NUMBER P209;
FORCEADD OFFPAGE..1
(-3425 -2475);
FORCEPROP 2 LAST $XR2 255 
J 0
(-3917 -2475);
DISPLAY 0.638298 (-3917 -2475);
PAINT MONO (-3917 -2475);
FORCEPROP 2 LAST $XR1 222 
J 0
(-3797 -2475);
DISPLAY 0.638298 (-3797 -2475);
PAINT MONO (-3797 -2475);
FORCEPROP 2 LAST $XR0 214 
J 0
(-3677 -2475);
DISPLAY 0.638298 (-3677 -2475);
PAINT MONO (-3677 -2475);
FORCEPROP 2 LAST CDS_LIB standard
J 0
(-3425 -2475);
PAINT MONO (-3425 -2475);
DISPLAY INVISIBLE (-3425 -2475);
FORCEPROP 1 LAST OFFPAGE TRUE
J 0
(-3100 -2600);
DISPLAY 0.872340 (-3100 -2600);
PAINT GREEN (-3100 -2600);
DISPLAY INVISIBLE (-3100 -2600);
FORCEPROP 1 LAST COMMENT_BODY TRUE
J 0
(-3300 -2575);
DISPLAY 0.872340 (-3300 -2575);
PAINT GREEN (-3300 -2575);
DISPLAY INVISIBLE (-3300 -2575);
FORCEPROP 2 LAST PATH I1
J 0
(-3675 -2425);
DISPLAY 1.021277 (-3675 -2425);
DISPLAY INVISIBLE (-3675 -2425);
FORCEADD UNIVERSAL_GND..1
(-3325 1825);
FORCEPROP 3 LASTPIN (-3325 1875) SIG_NAME GND\g
J 0
(-3315 1885);
DISPLAY 0.659574 (-3315 1885);
PAINT MONO (-3315 1885);
DISPLAY INVISIBLE (-3315 1885);
FORCEPROP 2 LAST ROOM IO_SLOT
J 1
(-3550 1900);
DISPLAY 0.744681 (-3550 1900);
DISPLAY INVISIBLE (-3550 1900);
FORCEPROP 2 LAST CDS_LIB logical_power
J 0
(-3325 1825);
PAINT MONO (-3325 1825);
DISPLAY INVISIBLE (-3325 1825);
FORCEPROP 1 LAST HDL_POWER GND
J 1
(-3300 1750);
DISPLAY 0.872340 (-3300 1750);
PAINT GREEN (-3300 1750);
DISPLAY INVISIBLE (-3300 1750);
FORCEPROP 1 LAST PATH I10
J 0
(-3250 1825);
DISPLAY 0.872340 (-3250 1825);
PAINT AQUA (-3250 1825);
DISPLAY INVISIBLE (-3250 1825);
FORCEADD Q_RES..2
(-3325 2050);
FORCEPROP 1 LAST PART_NUMBER CS21002FB06
J 0
(-3285 1925);
DISPLAY 0.638298 (-3285 1925);
DISPLAY INVISIBLE (-3285 1925);
FORCEPROP 1 LAST VALUE 1K
J 0
(-3280 2125);
DISPLAY 0.638298 (-3280 2125);
FORCEPROP 1 LAST MATERIAL EMPTY
J 0
(-3285 1975);
DISPLAY 0.638298 (-3285 1975);
PAINT RED (-3285 1975);
FORCEPROP 1 LAST PACK_TYPE 0402LF
J 0
(-3285 1875);
DISPLAY 0.638298 (-3285 1875);
FORCEPROP 1 LAST WATTAGE 1/16W
J 0
(-3285 2025);
DISPLAY 0.638298 (-3285 2025);
FORCEPROP 1 LAST TOLERANCE 1%
J 0
(-3280 2075);
DISPLAY 0.638298 (-3280 2075);
FORCEPROP 1 LAST $LOCATION R736
J 0
(-3280 2175);
DISPLAY 0.978723 (-3280 2175);
FORCEPROP 1 LASTPIN (-3325 2150) $PN 1
J 0
(-3320 2112);
DISPLAY 0.787234 (-3320 2112);
FORCEPROP 1 LASTPIN (-3325 1950) $PN 2
J 0
(-3320 1960);
DISPLAY 0.787234 (-3320 1960);
FORCEPROP 2 LAST CDS_LIB pure_quanta
J 0
(-3325 2050);
PAINT MONO (-3325 2050);
DISPLAY INVISIBLE (-3325 2050);
FORCEPROP 1 LAST PATH I11
J 0
(-3275 2225);
DISPLAY 0.978723 (-3275 2225);
PAINT WHITE (-3275 2225);
DISPLAY INVISIBLE (-3275 2225);
FORCEPROP 2 LAST CDS_LOCATION R736
J 0
(-3275 2275);
DISPLAY 1.021277 (-3275 2275);
DISPLAY INVISIBLE (-3275 2275);
FORCEPROP 2 LAST $SEC 1
J 0
(-3275 2275);
DISPLAY 0.680851 (-3275 2275);
PAINT MONO (-3275 2275);
DISPLAY INVISIBLE (-3275 2275);
FORCEPROP 2 LAST CDS_SEC 1
J 0
(-3275 2275);
DISPLAY 1.021277 (-3275 2275);
DISPLAY INVISIBLE (-3275 2275);
FORCEADD UNIVERSAL_POWER..1
(-3325 2775);
FORCEPROP 3 LASTPIN (-3325 2725) SIG_NAME P3V3_AUX\g
J 0
(-3315 2735);
DISPLAY 0.659574 (-3315 2735);
PAINT MONO (-3315 2735);
DISPLAY INVISIBLE (-3315 2735);
FORCEPROP 1 LAST HDL_POWER P3V3_AUX
J 1
(-3325 2825);
DISPLAY 0.872340 (-3325 2825);
PAINT GREEN (-3325 2825);
FORCEPROP 2 LAST CDS_LIB logical_power
J 0
(-3325 2775);
PAINT MONO (-3325 2775);
DISPLAY INVISIBLE (-3325 2775);
FORCEPROP 1 LAST PATH I12
J 0
(-3275 2800);
DISPLAY 0.872340 (-3275 2800);
PAINT AQUA (-3275 2800);
DISPLAY INVISIBLE (-3275 2800);
FORCEADD Q_RES..2
(-3325 2525);
FORCEPROP 1 LAST PART_NUMBER CS31002FB08
J 0
(-3285 2400);
DISPLAY 0.638298 (-3285 2400);
DISPLAY INVISIBLE (-3285 2400);
FORCEPROP 1 LAST TOLERANCE 1%
J 0
(-3280 2550);
DISPLAY 0.638298 (-3280 2550);
FORCEPROP 1 LAST VALUE 10K
J 0
(-3280 2600);
DISPLAY 0.638298 (-3280 2600);
FORCEPROP 1 LAST PACK_TYPE 0402LF
J 0
(-3285 2350);
DISPLAY 0.638298 (-3285 2350);
FORCEPROP 1 LAST MATERIAL CHIP
J 0
(-3285 2450);
DISPLAY 0.638298 (-3285 2450);
FORCEPROP 1 LAST WATTAGE 1/16W
J 0
(-3285 2500);
DISPLAY 0.638298 (-3285 2500);
FORCEPROP 1 LAST $LOCATION R735
J 0
(-3280 2650);
DISPLAY 0.978723 (-3280 2650);
FORCEPROP 1 LASTPIN (-3325 2625) $PN 1
J 0
(-3320 2587);
DISPLAY 0.787234 (-3320 2587);
FORCEPROP 1 LASTPIN (-3325 2425) $PN 2
J 0
(-3320 2435);
DISPLAY 0.787234 (-3320 2435);
FORCEPROP 2 LAST CDS_LIB pure_quanta
J 0
(-3325 2525);
PAINT MONO (-3325 2525);
DISPLAY INVISIBLE (-3325 2525);
FORCEPROP 1 LAST PATH I13
J 0
(-3275 2700);
DISPLAY 0.978723 (-3275 2700);
PAINT WHITE (-3275 2700);
DISPLAY INVISIBLE (-3275 2700);
FORCEPROP 2 LAST CDS_LOCATION R735
J 0
(-3275 2750);
DISPLAY 1.021277 (-3275 2750);
DISPLAY INVISIBLE (-3275 2750);
FORCEPROP 2 LAST $SEC 1
J 0
(-3275 2750);
DISPLAY 0.680851 (-3275 2750);
PAINT MONO (-3275 2750);
DISPLAY INVISIBLE (-3275 2750);
FORCEPROP 2 LAST CDS_SEC 1
J 0
(-3275 2750);
DISPLAY 1.021277 (-3275 2750);
DISPLAY INVISIBLE (-3275 2750);
FORCEADD Q_RES..1
(-1850 -500);
FORCEPROP 1 LAST PART_NUMBER CS31002FB08
J 0
(-1975 -425);
DISPLAY 0.638298 (-1975 -425);
DISPLAY INVISIBLE (-1975 -425);
FORCEPROP 1 LAST MATERIAL EMPTY
J 0
(-1525 -500);
DISPLAY 0.638298 (-1525 -500);
PAINT RED (-1525 -500);
FORCEPROP 1 LAST VALUE 10K
J 2
(-1650 -500);
DISPLAY 0.638298 (-1650 -500);
FORCEPROP 1 LAST TOLERANCE 1%
J 0
(-1625 -500);
DISPLAY 0.638298 (-1625 -500);
FORCEPROP 1 LAST $LOCATION R1660
J 0
(-2125 -500);
DISPLAY 0.638298 (-2125 -500);
FORCEPROP 1 LASTPIN (-1950 -500) $PN 1
J 0
(-1938 -488);
DISPLAY 0.787234 (-1938 -488);
FORCEPROP 1 LASTPIN (-1750 -500) $PN 2
J 0
(-1788 -488);
DISPLAY 0.787234 (-1788 -488);
FORCEPROP 1 LAST PACK_TYPE 0402LF
J 0
(-1975 -375);
DISPLAY 0.638298 (-1975 -375);
DISPLAY INVISIBLE (-1975 -375);
FORCEPROP 1 LAST WATTAGE 1/16W
J 2
(-1600 -375);
DISPLAY 0.638298 (-1600 -375);
DISPLAY INVISIBLE (-1600 -375);
FORCEPROP 2 LAST CDS_LIB pure_quanta
J 0
(-1850 -500);
PAINT MONO (-1850 -500);
DISPLAY INVISIBLE (-1850 -500);
FORCEPROP 1 LAST PATH I14
J 0
(-1900 -350);
DISPLAY 0.978723 (-1900 -350);
PAINT WHITE (-1900 -350);
DISPLAY INVISIBLE (-1900 -350);
FORCEPROP 2 LAST CDS_LOCATION R1660
J 0
(-1900 -300);
DISPLAY 1.021277 (-1900 -300);
DISPLAY INVISIBLE (-1900 -300);
FORCEPROP 2 LAST $SEC 1
J 0
(-1900 -300);
DISPLAY 0.680851 (-1900 -300);
PAINT MONO (-1900 -300);
DISPLAY INVISIBLE (-1900 -300);
FORCEPROP 2 LAST CDS_SEC 1
J 0
(-1900 -300);
DISPLAY 1.021277 (-1900 -300);
DISPLAY INVISIBLE (-1900 -300);
FORCEADD Q_RES..1
(-1850 -150);
FORCEPROP 1 LAST PART_NUMBER CS31002FB08
J 0
(-1975 -75);
DISPLAY 0.638298 (-1975 -75);
DISPLAY INVISIBLE (-1975 -75);
FORCEPROP 1 LAST MATERIAL EMPTY
J 0
(-1525 -150);
DISPLAY 0.638298 (-1525 -150);
PAINT RED (-1525 -150);
FORCEPROP 1 LAST TOLERANCE 1%
J 0
(-1625 -150);
DISPLAY 0.638298 (-1625 -150);
FORCEPROP 1 LAST VALUE 10K
J 2
(-1650 -150);
DISPLAY 0.638298 (-1650 -150);
FORCEPROP 1 LAST $LOCATION R1558
J 0
(-2125 -150);
DISPLAY 0.638298 (-2125 -150);
FORCEPROP 1 LASTPIN (-1950 -150) $PN 1
J 0
(-1938 -138);
DISPLAY 0.787234 (-1938 -138);
FORCEPROP 1 LASTPIN (-1750 -150) $PN 2
J 0
(-1788 -138);
DISPLAY 0.787234 (-1788 -138);
FORCEPROP 1 LAST PACK_TYPE 0402LF
J 0
(-1975 -25);
DISPLAY 0.638298 (-1975 -25);
DISPLAY INVISIBLE (-1975 -25);
FORCEPROP 1 LAST WATTAGE 1/16W
J 2
(-1600 -25);
DISPLAY 0.638298 (-1600 -25);
DISPLAY INVISIBLE (-1600 -25);
FORCEPROP 2 LAST CDS_LIB pure_quanta
J 0
(-1850 -150);
PAINT MONO (-1850 -150);
DISPLAY INVISIBLE (-1850 -150);
FORCEPROP 1 LAST PATH I15
J 0
(-1900 0);
DISPLAY 0.978723 (-1900 0);
PAINT WHITE (-1900 0);
DISPLAY INVISIBLE (-1900 0);
FORCEPROP 2 LAST CDS_LOCATION R1558
J 0
(-1900 50);
DISPLAY 1.021277 (-1900 50);
DISPLAY INVISIBLE (-1900 50);
FORCEPROP 2 LAST $SEC 1
J 0
(-1900 50);
DISPLAY 0.680851 (-1900 50);
PAINT MONO (-1900 50);
DISPLAY INVISIBLE (-1900 50);
FORCEPROP 2 LAST CDS_SEC 1
J 0
(-1900 50);
DISPLAY 1.021277 (-1900 50);
DISPLAY INVISIBLE (-1900 50);
FORCEADD Q_RES..1
(-1850 875);
FORCEPROP 1 LAST PART_NUMBER CS31002FB08
J 0
(-1975 950);
DISPLAY 0.638298 (-1975 950);
DISPLAY INVISIBLE (-1975 950);
FORCEPROP 1 LAST TOLERANCE 1%
J 0
(-1625 875);
DISPLAY 0.638298 (-1625 875);
FORCEPROP 1 LAST VALUE 10K
J 2
(-1650 875);
DISPLAY 0.638298 (-1650 875);
FORCEPROP 1 LAST MATERIAL CHIP
J 0
(-1525 875);
DISPLAY 0.638298 (-1525 875);
FORCEPROP 1 LAST $LOCATION R1401
J 0
(-2125 875);
DISPLAY 0.638298 (-2125 875);
FORCEPROP 1 LASTPIN (-1950 875) $PN 1
J 0
(-1938 887);
DISPLAY 0.787234 (-1938 887);
FORCEPROP 1 LASTPIN (-1750 875) $PN 2
J 0
(-1788 887);
DISPLAY 0.787234 (-1788 887);
FORCEPROP 1 LAST PACK_TYPE 0402LF
J 0
(-1975 1000);
DISPLAY 0.638298 (-1975 1000);
DISPLAY INVISIBLE (-1975 1000);
FORCEPROP 1 LAST WATTAGE 1/16W
J 2
(-1600 1000);
DISPLAY 0.638298 (-1600 1000);
DISPLAY INVISIBLE (-1600 1000);
FORCEPROP 2 LAST CDS_LIB pure_quanta
J 0
(-1850 875);
PAINT MONO (-1850 875);
DISPLAY INVISIBLE (-1850 875);
FORCEPROP 1 LAST PATH I16
J 0
(-1900 1025);
DISPLAY 0.978723 (-1900 1025);
PAINT WHITE (-1900 1025);
DISPLAY INVISIBLE (-1900 1025);
FORCEPROP 2 LAST CDS_LOCATION R1401
J 0
(-1900 1075);
DISPLAY 1.021277 (-1900 1075);
DISPLAY INVISIBLE (-1900 1075);
FORCEPROP 2 LAST $SEC 1
J 0
(-1900 1075);
DISPLAY 0.680851 (-1900 1075);
PAINT MONO (-1900 1075);
DISPLAY INVISIBLE (-1900 1075);
FORCEPROP 2 LAST CDS_SEC 1
J 0
(-1900 1075);
DISPLAY 1.021277 (-1900 1075);
DISPLAY INVISIBLE (-1900 1075);
FORCEADD Q_RES..1
(-1850 1175);
FORCEPROP 1 LAST PART_NUMBER CS31002FB08
J 0
(-1975 1250);
DISPLAY 0.638298 (-1975 1250);
DISPLAY INVISIBLE (-1975 1250);
FORCEPROP 1 LAST MATERIAL CHIP
J 0
(-1525 1175);
DISPLAY 0.638298 (-1525 1175);
FORCEPROP 1 LAST TOLERANCE 1%
J 0
(-1625 1175);
DISPLAY 0.638298 (-1625 1175);
FORCEPROP 1 LAST VALUE 10K
J 2
(-1650 1175);
DISPLAY 0.638298 (-1650 1175);
FORCEPROP 1 LAST $LOCATION R1399
J 0
(-2125 1175);
DISPLAY 0.638298 (-2125 1175);
FORCEPROP 1 LASTPIN (-1950 1175) $PN 1
J 0
(-1938 1187);
DISPLAY 0.787234 (-1938 1187);
FORCEPROP 1 LASTPIN (-1750 1175) $PN 2
J 0
(-1788 1187);
DISPLAY 0.787234 (-1788 1187);
FORCEPROP 1 LAST PACK_TYPE 0402LF
J 0
(-1975 1300);
DISPLAY 0.638298 (-1975 1300);
DISPLAY INVISIBLE (-1975 1300);
FORCEPROP 1 LAST WATTAGE 1/16W
J 2
(-1600 1300);
DISPLAY 0.638298 (-1600 1300);
DISPLAY INVISIBLE (-1600 1300);
FORCEPROP 2 LAST CDS_LIB pure_quanta
J 0
(-1850 1175);
PAINT MONO (-1850 1175);
DISPLAY INVISIBLE (-1850 1175);
FORCEPROP 1 LAST PATH I17
J 0
(-1900 1325);
DISPLAY 0.978723 (-1900 1325);
PAINT WHITE (-1900 1325);
DISPLAY INVISIBLE (-1900 1325);
FORCEPROP 2 LAST CDS_LOCATION R1399
J 0
(-1900 1375);
DISPLAY 1.021277 (-1900 1375);
DISPLAY INVISIBLE (-1900 1375);
FORCEPROP 2 LAST $SEC 1
J 0
(-1900 1375);
DISPLAY 0.680851 (-1900 1375);
PAINT MONO (-1900 1375);
DISPLAY INVISIBLE (-1900 1375);
FORCEPROP 2 LAST CDS_SEC 1
J 0
(-1900 1375);
DISPLAY 1.021277 (-1900 1375);
DISPLAY INVISIBLE (-1900 1375);
FORCEADD OFFPAGE..2
(-2200 2275);
FORCEPROP 2 LAST $XR0 215 
J 0
(-2011 2275);
DISPLAY 0.638298 (-2011 2275);
PAINT MONO (-2011 2275);
FORCEPROP 2 LAST CDS_LIB standard
J 0
(-2200 2275);
PAINT MONO (-2200 2275);
DISPLAY INVISIBLE (-2200 2275);
FORCEPROP 1 LAST OFFPAGE TRUE
J 0
(-1875 2150);
DISPLAY 0.872340 (-1875 2150);
DISPLAY INVISIBLE (-1875 2150);
FORCEPROP 1 LAST COMMENT_BODY TRUE
J 0
(-2245 2180);
DISPLAY 0.872340 (-2245 2180);
PAINT GREEN (-2245 2180);
DISPLAY INVISIBLE (-2245 2180);
FORCEPROP 2 LAST PATH I18
J 0
(-2000 2325);
DISPLAY 1.021277 (-2000 2325);
DISPLAY INVISIBLE (-2000 2325);
FORCEADD UNIVERSAL_POWER..1
(-1300 1700);
FORCEPROP 3 LASTPIN (-1300 1650) SIG_NAME P3V3_AUX\g
J 0
(-1290 1660);
DISPLAY 0.659574 (-1290 1660);
PAINT MONO (-1290 1660);
DISPLAY INVISIBLE (-1290 1660);
FORCEPROP 1 LAST HDL_POWER P3V3_AUX
J 1
(-1300 1750);
DISPLAY 0.872340 (-1300 1750);
PAINT GREEN (-1300 1750);
FORCEPROP 2 LAST CDS_LIB logical_power
J 0
(-1300 1700);
PAINT MONO (-1300 1700);
DISPLAY INVISIBLE (-1300 1700);
FORCEPROP 1 LAST PATH I19
J 0
(-1250 1725);
DISPLAY 0.872340 (-1250 1725);
PAINT AQUA (-1250 1725);
DISPLAY INVISIBLE (-1250 1725);
FORCEADD OFFPAGE..1
(-3425 -2325);
FORCEPROP 2 LAST $XR2 255 
J 0
(-3917 -2325);
DISPLAY 0.638298 (-3917 -2325);
PAINT MONO (-3917 -2325);
FORCEPROP 2 LAST $XR1 222 
J 0
(-3797 -2325);
DISPLAY 0.638298 (-3797 -2325);
PAINT MONO (-3797 -2325);
FORCEPROP 2 LAST $XR0 214 
J 0
(-3677 -2325);
DISPLAY 0.638298 (-3677 -2325);
PAINT MONO (-3677 -2325);
FORCEPROP 2 LAST CDS_LIB standard
J 0
(-3425 -2325);
PAINT MONO (-3425 -2325);
DISPLAY INVISIBLE (-3425 -2325);
FORCEPROP 1 LAST OFFPAGE TRUE
J 0
(-3100 -2450);
DISPLAY 0.872340 (-3100 -2450);
PAINT GREEN (-3100 -2450);
DISPLAY INVISIBLE (-3100 -2450);
FORCEPROP 1 LAST COMMENT_BODY TRUE
J 0
(-3300 -2425);
DISPLAY 0.872340 (-3300 -2425);
PAINT GREEN (-3300 -2425);
DISPLAY INVISIBLE (-3300 -2425);
FORCEPROP 2 LAST PATH I2
J 0
(-3675 -2275);
DISPLAY 1.021277 (-3675 -2275);
DISPLAY INVISIBLE (-3675 -2275);
FORCEADD UNIVERSAL_GND..1
(2325 -2850);
FORCEPROP 3 LASTPIN (2325 -2800) SIG_NAME GND\g
J 0
(2335 -2790);
DISPLAY 0.659574 (2335 -2790);
PAINT MONO (2335 -2790);
DISPLAY INVISIBLE (2335 -2790);
FORCEPROP 2 LAST ROOM IO_SLOT
J 1
(2100 -2775);
DISPLAY 0.744681 (2100 -2775);
DISPLAY INVISIBLE (2100 -2775);
FORCEPROP 2 LAST CDS_LIB logical_power
J 0
(2325 -2850);
PAINT MONO (2325 -2850);
DISPLAY INVISIBLE (2325 -2850);
FORCEPROP 1 LAST HDL_POWER GND
J 1
(2350 -2925);
DISPLAY 0.872340 (2350 -2925);
PAINT GREEN (2350 -2925);
DISPLAY INVISIBLE (2350 -2925);
FORCEPROP 1 LAST PATH I20
J 0
(2400 -2850);
DISPLAY 0.872340 (2400 -2850);
PAINT AQUA (2400 -2850);
DISPLAY INVISIBLE (2400 -2850);
FORCEADD Q_RES..1
(1775 -1825);
FORCEPROP 1 LAST PART_NUMBER CS21002FB06
J 0
(1650 -1775);
DISPLAY 0.638298 (1650 -1775);
DISPLAY INVISIBLE (1650 -1775);
FORCEPROP 1 LAST VALUE 1K
J 2
(1975 -1825);
DISPLAY 0.638298 (1975 -1825);
FORCEPROP 1 LAST MATERIAL EMPTY
J 0
(2100 -1825);
DISPLAY 0.638298 (2100 -1825);
PAINT RED (2100 -1825);
FORCEPROP 1 LAST TOLERANCE 1%
J 0
(2000 -1825);
DISPLAY 0.638298 (2000 -1825);
FORCEPROP 1 LAST $LOCATION R1494
J 0
(1500 -1825);
DISPLAY 0.638298 (1500 -1825);
FORCEPROP 1 LASTPIN (1675 -1825) $PN 1
J 0
(1687 -1813);
DISPLAY 0.787234 (1687 -1813);
FORCEPROP 1 LASTPIN (1875 -1825) $PN 2
J 0
(1837 -1813);
DISPLAY 0.787234 (1837 -1813);
FORCEPROP 2 LAST CDS_LIB pure_quanta
J 0
(1775 -1825);
PAINT MONO (1775 -1825);
DISPLAY INVISIBLE (1775 -1825);
FORCEPROP 1 LAST WATTAGE 1/16W
J 2
(2050 -1725);
DISPLAY 0.638298 (2050 -1725);
DISPLAY INVISIBLE (2050 -1725);
FORCEPROP 1 LAST PACK_TYPE 0402LF
J 0
(1650 -1725);
DISPLAY 0.638298 (1650 -1725);
DISPLAY INVISIBLE (1650 -1725);
FORCEPROP 1 LAST PATH I21
J 0
(1725 -1675);
DISPLAY 0.978723 (1725 -1675);
PAINT WHITE (1725 -1675);
DISPLAY INVISIBLE (1725 -1675);
FORCEPROP 2 LAST CDS_LOCATION R1494
J 0
(1725 -1625);
DISPLAY 1.021277 (1725 -1625);
DISPLAY INVISIBLE (1725 -1625);
FORCEPROP 2 LAST $SEC 1
J 0
(1725 -1625);
DISPLAY 0.680851 (1725 -1625);
PAINT MONO (1725 -1625);
DISPLAY INVISIBLE (1725 -1625);
FORCEPROP 2 LAST CDS_SEC 1
J 0
(1725 -1625);
DISPLAY 1.021277 (1725 -1625);
DISPLAY INVISIBLE (1725 -1625);
FORCEADD Q_RES..1
(1775 -1725);
FORCEPROP 1 LAST PART_NUMBER CS31002FB08
J 0
(1650 -1650);
DISPLAY 0.638298 (1650 -1650);
DISPLAY INVISIBLE (1650 -1650);
FORCEPROP 1 LAST MATERIAL EMPTY
J 0
(2100 -1725);
DISPLAY 0.638298 (2100 -1725);
PAINT RED (2100 -1725);
FORCEPROP 1 LAST TOLERANCE 1%
J 0
(2000 -1725);
DISPLAY 0.638298 (2000 -1725);
FORCEPROP 1 LAST VALUE 10K
J 2
(1975 -1725);
DISPLAY 0.638298 (1975 -1725);
FORCEPROP 1 LAST $LOCATION R1312
J 0
(1500 -1725);
DISPLAY 0.638298 (1500 -1725);
FORCEPROP 1 LASTPIN (1675 -1725) $PN 1
J 0
(1687 -1713);
DISPLAY 0.787234 (1687 -1713);
FORCEPROP 1 LASTPIN (1875 -1725) $PN 2
J 0
(1837 -1713);
DISPLAY 0.787234 (1837 -1713);
FORCEPROP 2 LAST CDS_LIB pure_quanta
J 0
(1775 -1725);
PAINT MONO (1775 -1725);
DISPLAY INVISIBLE (1775 -1725);
FORCEPROP 1 LAST PACK_TYPE 0402LF
J 0
(1650 -1600);
DISPLAY 0.638298 (1650 -1600);
DISPLAY INVISIBLE (1650 -1600);
FORCEPROP 1 LAST WATTAGE 1/16W
J 2
(2025 -1600);
DISPLAY 0.638298 (2025 -1600);
DISPLAY INVISIBLE (2025 -1600);
FORCEPROP 1 LAST PATH I22
J 0
(1725 -1575);
DISPLAY 0.978723 (1725 -1575);
PAINT WHITE (1725 -1575);
DISPLAY INVISIBLE (1725 -1575);
FORCEPROP 2 LAST CDS_LOCATION R1312
J 0
(1725 -1525);
DISPLAY 1.021277 (1725 -1525);
DISPLAY INVISIBLE (1725 -1525);
FORCEPROP 2 LAST $SEC 1
J 0
(1725 -1525);
DISPLAY 0.680851 (1725 -1525);
PAINT MONO (1725 -1525);
DISPLAY INVISIBLE (1725 -1525);
FORCEPROP 2 LAST CDS_SEC 1
J 0
(1725 -1525);
DISPLAY 1.021277 (1725 -1525);
DISPLAY INVISIBLE (1725 -1525);
FORCEADD Q_RES..1
(1775 -1625);
FORCEPROP 1 LAST PART_NUMBER CS31002FB08
J 0
(1650 -1550);
DISPLAY 0.638298 (1650 -1550);
DISPLAY INVISIBLE (1650 -1550);
FORCEPROP 1 LAST MATERIAL EMPTY
J 0
(2100 -1625);
DISPLAY 0.638298 (2100 -1625);
PAINT RED (2100 -1625);
FORCEPROP 1 LAST VALUE 10K
J 2
(1975 -1625);
DISPLAY 0.638298 (1975 -1625);
FORCEPROP 1 LAST TOLERANCE 1%
J 0
(2000 -1625);
DISPLAY 0.638298 (2000 -1625);
FORCEPROP 1 LAST $LOCATION R1308
J 0
(1500 -1625);
DISPLAY 0.638298 (1500 -1625);
FORCEPROP 1 LASTPIN (1675 -1625) $PN 1
J 0
(1687 -1613);
DISPLAY 0.787234 (1687 -1613);
FORCEPROP 1 LASTPIN (1875 -1625) $PN 2
J 0
(1837 -1613);
DISPLAY 0.787234 (1837 -1613);
FORCEPROP 1 LAST WATTAGE 1/16W
J 2
(2025 -1500);
DISPLAY 0.638298 (2025 -1500);
DISPLAY INVISIBLE (2025 -1500);
FORCEPROP 1 LAST PACK_TYPE 0402LF
J 0
(1650 -1500);
DISPLAY 0.638298 (1650 -1500);
DISPLAY INVISIBLE (1650 -1500);
FORCEPROP 2 LAST CDS_LIB pure_quanta
J 0
(1775 -1625);
PAINT MONO (1775 -1625);
DISPLAY INVISIBLE (1775 -1625);
FORCEPROP 1 LAST PATH I23
J 0
(1725 -1475);
DISPLAY 0.978723 (1725 -1475);
PAINT WHITE (1725 -1475);
DISPLAY INVISIBLE (1725 -1475);
FORCEPROP 2 LAST CDS_LOCATION R1308
J 0
(1725 -1425);
DISPLAY 1.021277 (1725 -1425);
DISPLAY INVISIBLE (1725 -1425);
FORCEPROP 2 LAST $SEC 1
J 0
(1725 -1425);
DISPLAY 0.680851 (1725 -1425);
PAINT MONO (1725 -1425);
DISPLAY INVISIBLE (1725 -1425);
FORCEPROP 2 LAST CDS_SEC 1
J 0
(1725 -1425);
DISPLAY 1.021277 (1725 -1425);
DISPLAY INVISIBLE (1725 -1425);
FORCEADD Q_RES..1
(1775 -1525);
FORCEPROP 1 LAST PART_NUMBER CS31002FB08
J 0
(1650 -1450);
DISPLAY 0.638298 (1650 -1450);
DISPLAY INVISIBLE (1650 -1450);
FORCEPROP 1 LAST MATERIAL EMPTY
J 0
(2100 -1525);
DISPLAY 0.638298 (2100 -1525);
PAINT RED (2100 -1525);
FORCEPROP 1 LAST VALUE 10K
J 2
(1975 -1525);
DISPLAY 0.638298 (1975 -1525);
FORCEPROP 1 LAST TOLERANCE 1%
J 0
(2000 -1525);
DISPLAY 0.638298 (2000 -1525);
FORCEPROP 1 LAST $LOCATION R1742
J 0
(1500 -1525);
DISPLAY 0.638298 (1500 -1525);
FORCEPROP 1 LASTPIN (1675 -1525) $PN 1
J 0
(1687 -1513);
DISPLAY 0.787234 (1687 -1513);
FORCEPROP 1 LASTPIN (1875 -1525) $PN 2
J 0
(1837 -1513);
DISPLAY 0.787234 (1837 -1513);
FORCEPROP 1 LAST PACK_TYPE 0402LF
J 0
(1650 -1400);
DISPLAY 0.638298 (1650 -1400);
DISPLAY INVISIBLE (1650 -1400);
FORCEPROP 1 LAST WATTAGE 1/16W
J 2
(2025 -1400);
DISPLAY 0.638298 (2025 -1400);
DISPLAY INVISIBLE (2025 -1400);
FORCEPROP 2 LAST CDS_LIB pure_quanta
J 0
(1775 -1525);
PAINT MONO (1775 -1525);
DISPLAY INVISIBLE (1775 -1525);
FORCEPROP 1 LAST PATH I24
J 0
(1725 -1375);
DISPLAY 0.978723 (1725 -1375);
PAINT WHITE (1725 -1375);
DISPLAY INVISIBLE (1725 -1375);
FORCEPROP 2 LAST CDS_LOCATION R1742
J 0
(1725 -1325);
DISPLAY 1.021277 (1725 -1325);
DISPLAY INVISIBLE (1725 -1325);
FORCEPROP 2 LAST $SEC 1
J 0
(1725 -1325);
DISPLAY 0.680851 (1725 -1325);
PAINT MONO (1725 -1325);
DISPLAY INVISIBLE (1725 -1325);
FORCEPROP 2 LAST CDS_SEC 1
J 0
(1725 -1325);
DISPLAY 1.021277 (1725 -1325);
DISPLAY INVISIBLE (1725 -1325);
FORCEADD OFFPAGE..1
(125 -1075);
FORCEPROP 2 LAST $XR0 215 
J 0
(-157 -1075);
DISPLAY 0.638298 (-157 -1075);
PAINT MONO (-157 -1075);
FORCEPROP 2 LAST CDS_LIB standard
J 0
(125 -1075);
PAINT MONO (125 -1075);
DISPLAY INVISIBLE (125 -1075);
FORCEPROP 1 LAST OFFPAGE TRUE
J 0
(450 -1200);
DISPLAY 0.872340 (450 -1200);
PAINT GREEN (450 -1200);
DISPLAY INVISIBLE (450 -1200);
FORCEPROP 1 LAST COMMENT_BODY TRUE
J 0
(250 -1175);
DISPLAY 0.872340 (250 -1175);
PAINT GREEN (250 -1175);
DISPLAY INVISIBLE (250 -1175);
FORCEPROP 2 LAST PATH I25
J 0
(-150 -1025);
DISPLAY 1.021277 (-150 -1025);
DISPLAY INVISIBLE (-150 -1025);
FORCEADD OFFPAGE..1
(125 -1175);
FORCEPROP 2 LAST $XR0 215 
J 0
(-157 -1175);
DISPLAY 0.638298 (-157 -1175);
PAINT MONO (-157 -1175);
FORCEPROP 2 LAST CDS_LIB standard
J 0
(125 -1175);
PAINT MONO (125 -1175);
DISPLAY INVISIBLE (125 -1175);
FORCEPROP 1 LAST OFFPAGE TRUE
J 0
(450 -1300);
DISPLAY 0.872340 (450 -1300);
PAINT GREEN (450 -1300);
DISPLAY INVISIBLE (450 -1300);
FORCEPROP 1 LAST COMMENT_BODY TRUE
J 0
(250 -1275);
DISPLAY 0.872340 (250 -1275);
PAINT GREEN (250 -1275);
DISPLAY INVISIBLE (250 -1275);
FORCEPROP 2 LAST PATH I26
J 0
(-150 -1125);
DISPLAY 1.021277 (-150 -1125);
DISPLAY INVISIBLE (-150 -1125);
FORCEADD OFFPAGE..1
(125 -975);
FORCEPROP 2 LAST $XR0 214 
J 0
(-157 -975);
DISPLAY 0.638298 (-157 -975);
PAINT MONO (-157 -975);
FORCEPROP 2 LAST CDS_LIB standard
J 0
(125 -975);
PAINT MONO (125 -975);
DISPLAY INVISIBLE (125 -975);
FORCEPROP 1 LAST OFFPAGE TRUE
J 0
(450 -1100);
DISPLAY 0.872340 (450 -1100);
PAINT GREEN (450 -1100);
DISPLAY INVISIBLE (450 -1100);
FORCEPROP 1 LAST COMMENT_BODY TRUE
J 0
(250 -1075);
DISPLAY 0.872340 (250 -1075);
PAINT GREEN (250 -1075);
DISPLAY INVISIBLE (250 -1075);
FORCEPROP 2 LAST PATH I27
J 0
(-150 -925);
DISPLAY 1.021277 (-150 -925);
DISPLAY INVISIBLE (-150 -925);
FORCEADD OFFPAGE..1
(125 -875);
FORCEPROP 2 LAST $XR0 214 
J 0
(-157 -875);
DISPLAY 0.638298 (-157 -875);
PAINT MONO (-157 -875);
FORCEPROP 2 LAST CDS_LIB standard
J 0
(125 -875);
PAINT MONO (125 -875);
DISPLAY INVISIBLE (125 -875);
FORCEPROP 1 LAST OFFPAGE TRUE
J 0
(450 -1000);
DISPLAY 0.872340 (450 -1000);
PAINT GREEN (450 -1000);
DISPLAY INVISIBLE (450 -1000);
FORCEPROP 1 LAST COMMENT_BODY TRUE
J 0
(250 -975);
DISPLAY 0.872340 (250 -975);
PAINT GREEN (250 -975);
DISPLAY INVISIBLE (250 -975);
FORCEPROP 2 LAST PATH I28
J 0
(-150 -825);
DISPLAY 1.021277 (-150 -825);
DISPLAY INVISIBLE (-150 -825);
FORCEADD OFFPAGE..1
(125 -475);
FORCEPROP 2 LAST $XR1 215 
J 0
(-277 -475);
DISPLAY 0.638298 (-277 -475);
PAINT MONO (-277 -475);
FORCEPROP 2 LAST $XR0 240 
J 0
(-157 -475);
DISPLAY 0.638298 (-157 -475);
PAINT MONO (-157 -475);
FORCEPROP 2 LAST CDS_LIB standard
J 0
(125 -475);
PAINT MONO (125 -475);
DISPLAY INVISIBLE (125 -475);
FORCEPROP 1 LAST OFFPAGE TRUE
J 0
(450 -600);
DISPLAY 0.872340 (450 -600);
PAINT GREEN (450 -600);
DISPLAY INVISIBLE (450 -600);
FORCEPROP 1 LAST COMMENT_BODY TRUE
J 0
(250 -575);
DISPLAY 0.872340 (250 -575);
PAINT GREEN (250 -575);
DISPLAY INVISIBLE (250 -575);
FORCEPROP 2 LAST PATH I29
J 0
(-150 -425);
DISPLAY 1.021277 (-150 -425);
DISPLAY INVISIBLE (-150 -425);
FORCEADD Q_CAP..2
(-1525 -2325);
FORCEPROP 1 LAST PART_NUMBER CH11006JB00
J 1
(-1525 -2250);
DISPLAY 0.617021 (-1525 -2250);
PAINT BLUE (-1525 -2250);
DISPLAY INVISIBLE (-1525 -2250);
FORCEPROP 1 LAST VOLTAGE 50V
J 0
(-1400 -2200);
DISPLAY 0.617021 (-1400 -2200);
PAINT SKYBLUE (-1400 -2200);
FORCEPROP 1 LAST PACK_TYPE 0402
J 1
(-1500 -2200);
DISPLAY 0.617021 (-1500 -2200);
PAINT SKYBLUE (-1500 -2200);
FORCEPROP 1 LAST VALUE 100PF
J 2
(-1250 -2325);
DISPLAY 0.617021 (-1250 -2325);
PAINT SKYBLUE (-1250 -2325);
FORCEPROP 1 LAST TOLERANCE 5%
J 2
(-1150 -2325);
DISPLAY 0.617021 (-1150 -2325);
PAINT SKYBLUE (-1150 -2325);
FORCEPROP 1 LAST MATERIAL NPO
J 0
(-1700 -2200);
DISPLAY 0.617021 (-1700 -2200);
PAINT SKYBLUE (-1700 -2200);
FORCEPROP 1 LAST LOCATION C1209
J 1
(-1750 -2325);
DISPLAY 0.617021 (-1750 -2325);
PAINT AQUA (-1750 -2325);
FORCEPROP 1 LASTPIN (-1625 -2325) $PN 1
J 0
(-1635 -2310);
DISPLAY 0.787234 (-1635 -2310);
PAINT MONO (-1635 -2310);
FORCEPROP 1 LASTPIN (-1425 -2325) $PN 2
J 0
(-1440 -2310);
DISPLAY 0.787234 (-1440 -2310);
PAINT MONO (-1440 -2310);
FORCEPROP 2 LAST CDS_LIB pure_quanta
J 0
(-1525 -2325);
DISPLAY INVISIBLE (-1525 -2325);
FORCEPROP 1 LAST PATH I3
J 0
(-1525 -2125);
DISPLAY 0.978723 (-1525 -2125);
PAINT WHITE (-1525 -2125);
DISPLAY INVISIBLE (-1525 -2125);
FORCEPROP 0 LAST $SEC 1
J 0
(-1400 -2150);
DISPLAY 0.680851 (-1400 -2150);
PAINT MONO (-1400 -2150);
DISPLAY INVISIBLE (-1400 -2150);
FORCEPROP 0 LAST CDS_SEC 1
J 0
(-1400 -2150);
DISPLAY 1.021277 (-1400 -2150);
DISPLAY INVISIBLE (-1400 -2150);
FORCEADD OFFPAGE..1
(125 -350);
FORCEPROP 2 LAST $XR1 182 
J 0
(-277 -350);
DISPLAY 0.638298 (-277 -350);
PAINT MONO (-277 -350);
FORCEPROP 2 LAST $XR0 223 
J 0
(-157 -350);
DISPLAY 0.638298 (-157 -350);
PAINT MONO (-157 -350);
FORCEPROP 2 LAST CDS_LIB standard
J 0
(125 -350);
PAINT MONO (125 -350);
DISPLAY INVISIBLE (125 -350);
FORCEPROP 1 LAST OFFPAGE TRUE
J 0
(450 -475);
DISPLAY 0.872340 (450 -475);
PAINT GREEN (450 -475);
DISPLAY INVISIBLE (450 -475);
FORCEPROP 1 LAST COMMENT_BODY TRUE
J 0
(250 -450);
DISPLAY 0.872340 (250 -450);
PAINT GREEN (250 -450);
DISPLAY INVISIBLE (250 -450);
FORCEPROP 2 LAST PATH I30
J 0
(-150 -300);
DISPLAY 1.021277 (-150 -300);
DISPLAY INVISIBLE (-150 -300);
FORCEADD OFFPAGE..1
(125 -50);
FORCEPROP 2 LAST $XR1 221 
J 0
(-277 -50);
DISPLAY 0.638298 (-277 -50);
PAINT MONO (-277 -50);
FORCEPROP 2 LAST $XR0 216 
J 0
(-157 -50);
DISPLAY 0.638298 (-157 -50);
PAINT MONO (-157 -50);
FORCEPROP 2 LAST CDS_LIB standard
J 0
(125 -50);
PAINT MONO (125 -50);
DISPLAY INVISIBLE (125 -50);
FORCEPROP 1 LAST OFFPAGE TRUE
J 0
(450 -175);
DISPLAY 0.872340 (450 -175);
PAINT GREEN (450 -175);
DISPLAY INVISIBLE (450 -175);
FORCEPROP 1 LAST COMMENT_BODY TRUE
J 0
(250 -150);
DISPLAY 0.872340 (250 -150);
PAINT GREEN (250 -150);
DISPLAY INVISIBLE (250 -150);
FORCEPROP 2 LAST PATH I31
J 0
(-150 0);
DISPLAY 1.021277 (-150 0);
DISPLAY INVISIBLE (-150 0);
FORCEADD OFFPAGE..1
(125 700);
FORCEPROP 2 LAST $XR1 215 
J 0
(-277 700);
DISPLAY 0.638298 (-277 700);
PAINT MONO (-277 700);
FORCEPROP 2 LAST $XR0 205 
J 0
(-157 700);
DISPLAY 0.638298 (-157 700);
PAINT MONO (-157 700);
FORCEPROP 2 LAST CDS_LIB standard
J 0
(125 700);
PAINT MONO (125 700);
DISPLAY INVISIBLE (125 700);
FORCEPROP 1 LAST OFFPAGE TRUE
J 0
(450 575);
DISPLAY 0.872340 (450 575);
PAINT GREEN (450 575);
DISPLAY INVISIBLE (450 575);
FORCEPROP 1 LAST COMMENT_BODY TRUE
J 0
(250 600);
DISPLAY 0.872340 (250 600);
PAINT GREEN (250 600);
DISPLAY INVISIBLE (250 600);
FORCEPROP 2 LAST PATH I32
J 0
(-150 750);
DISPLAY 1.021277 (-150 750);
DISPLAY INVISIBLE (-150 750);
FORCEADD OFFPAGE..1
(125 400);
FORCEPROP 2 LAST $XR1 218 
J 0
(-277 400);
DISPLAY 0.638298 (-277 400);
PAINT MONO (-277 400);
FORCEPROP 2 LAST $XR0 215 
J 0
(-157 400);
DISPLAY 0.638298 (-157 400);
PAINT MONO (-157 400);
FORCEPROP 2 LAST CDS_LIB standard
J 0
(125 400);
PAINT MONO (125 400);
DISPLAY INVISIBLE (125 400);
FORCEPROP 1 LAST OFFPAGE TRUE
J 0
(450 275);
DISPLAY 0.872340 (450 275);
PAINT GREEN (450 275);
DISPLAY INVISIBLE (450 275);
FORCEPROP 1 LAST COMMENT_BODY TRUE
J 0
(250 300);
DISPLAY 0.872340 (250 300);
PAINT GREEN (250 300);
DISPLAY INVISIBLE (250 300);
FORCEPROP 2 LAST PATH I33
J 0
(-150 450);
DISPLAY 1.021277 (-150 450);
DISPLAY INVISIBLE (-150 450);
FORCEADD OFFPAGE..1
(125 850);
FORCEPROP 2 LAST $XR2 161 
J 0
(-397 850);
DISPLAY 0.638298 (-397 850);
PAINT MONO (-397 850);
FORCEPROP 2 LAST $XR1 155 
J 0
(-277 850);
DISPLAY 0.638298 (-277 850);
PAINT MONO (-277 850);
FORCEPROP 2 LAST $XR0 215 
J 0
(-157 850);
DISPLAY 0.638298 (-157 850);
PAINT MONO (-157 850);
FORCEPROP 2 LAST CDS_LIB standard
J 0
(125 850);
PAINT MONO (125 850);
DISPLAY INVISIBLE (125 850);
FORCEPROP 1 LAST OFFPAGE TRUE
J 0
(450 725);
DISPLAY 0.872340 (450 725);
PAINT GREEN (450 725);
DISPLAY INVISIBLE (450 725);
FORCEPROP 1 LAST COMMENT_BODY TRUE
J 0
(250 750);
DISPLAY 0.872340 (250 750);
PAINT GREEN (250 750);
DISPLAY INVISIBLE (250 750);
FORCEPROP 2 LAST PATH I34
J 0
(-150 900);
DISPLAY 1.021277 (-150 900);
DISPLAY INVISIBLE (-150 900);
FORCEADD Q_RES..1
(1775 -1075);
FORCEPROP 1 LAST PART_NUMBER CS31002FB08
J 0
(1650 -1000);
DISPLAY 0.638298 (1650 -1000);
DISPLAY INVISIBLE (1650 -1000);
FORCEPROP 1 LAST MATERIAL CHIP
J 0
(2100 -1075);
DISPLAY 0.638298 (2100 -1075);
FORCEPROP 1 LAST TOLERANCE 1%
J 0
(2000 -1075);
DISPLAY 0.638298 (2000 -1075);
FORCEPROP 1 LAST VALUE 10K
J 2
(1975 -1075);
DISPLAY 0.638298 (1975 -1075);
FORCEPROP 1 LAST $LOCATION R1492
J 0
(1500 -1075);
DISPLAY 0.638298 (1500 -1075);
FORCEPROP 1 LASTPIN (1675 -1075) $PN 1
J 0
(1687 -1063);
DISPLAY 0.787234 (1687 -1063);
FORCEPROP 1 LASTPIN (1875 -1075) $PN 2
J 0
(1837 -1063);
DISPLAY 0.787234 (1837 -1063);
FORCEPROP 2 LAST CDS_LIB pure_quanta
J 0
(1775 -1075);
PAINT MONO (1775 -1075);
DISPLAY INVISIBLE (1775 -1075);
FORCEPROP 1 LAST PACK_TYPE 0402LF
J 0
(1650 -950);
DISPLAY 0.638298 (1650 -950);
DISPLAY INVISIBLE (1650 -950);
FORCEPROP 1 LAST WATTAGE 1/16W
J 2
(2025 -950);
DISPLAY 0.638298 (2025 -950);
DISPLAY INVISIBLE (2025 -950);
FORCEPROP 1 LAST PATH I35
J 0
(1725 -925);
DISPLAY 0.978723 (1725 -925);
PAINT WHITE (1725 -925);
DISPLAY INVISIBLE (1725 -925);
FORCEPROP 2 LAST CDS_LOCATION R1492
J 0
(1725 -875);
DISPLAY 1.021277 (1725 -875);
DISPLAY INVISIBLE (1725 -875);
FORCEPROP 2 LAST $SEC 1
J 0
(1725 -875);
DISPLAY 0.680851 (1725 -875);
PAINT MONO (1725 -875);
DISPLAY INVISIBLE (1725 -875);
FORCEPROP 2 LAST CDS_SEC 1
J 0
(1725 -875);
DISPLAY 1.021277 (1725 -875);
DISPLAY INVISIBLE (1725 -875);
FORCEADD Q_RES..1
(1775 -975);
FORCEPROP 1 LAST PART_NUMBER CS21002FB06
J 0
(1650 -925);
DISPLAY 0.638298 (1650 -925);
DISPLAY INVISIBLE (1650 -925);
FORCEPROP 1 LAST VALUE 1K
J 2
(1975 -975);
DISPLAY 0.638298 (1975 -975);
FORCEPROP 1 LAST TOLERANCE 1%
J 0
(2000 -975);
DISPLAY 0.638298 (2000 -975);
FORCEPROP 1 LAST MATERIAL CHIP
J 0
(2100 -975);
DISPLAY 0.638298 (2100 -975);
FORCEPROP 1 LAST $LOCATION R1474
J 0
(1500 -975);
DISPLAY 0.638298 (1500 -975);
FORCEPROP 1 LASTPIN (1675 -975) $PN 1
J 0
(1687 -963);
DISPLAY 0.787234 (1687 -963);
FORCEPROP 1 LASTPIN (1875 -975) $PN 2
J 0
(1837 -963);
DISPLAY 0.787234 (1837 -963);
FORCEPROP 1 LAST PACK_TYPE 0402LF
J 0
(1650 -875);
DISPLAY 0.638298 (1650 -875);
DISPLAY INVISIBLE (1650 -875);
FORCEPROP 1 LAST WATTAGE 1/16W
J 2
(2050 -875);
DISPLAY 0.638298 (2050 -875);
DISPLAY INVISIBLE (2050 -875);
FORCEPROP 2 LAST CDS_LIB pure_quanta
J 0
(1775 -975);
PAINT MONO (1775 -975);
DISPLAY INVISIBLE (1775 -975);
FORCEPROP 1 LAST PATH I36
J 0
(1725 -825);
DISPLAY 0.978723 (1725 -825);
PAINT WHITE (1725 -825);
DISPLAY INVISIBLE (1725 -825);
FORCEPROP 2 LAST CDS_LOCATION R1474
J 0
(1725 -775);
DISPLAY 1.021277 (1725 -775);
DISPLAY INVISIBLE (1725 -775);
FORCEPROP 2 LAST $SEC 1
J 0
(1725 -775);
DISPLAY 0.680851 (1725 -775);
PAINT MONO (1725 -775);
DISPLAY INVISIBLE (1725 -775);
FORCEPROP 2 LAST CDS_SEC 1
J 0
(1725 -775);
DISPLAY 1.021277 (1725 -775);
DISPLAY INVISIBLE (1725 -775);
FORCEADD Q_RES..1
(1775 -875);
FORCEPROP 1 LAST PART_NUMBER CS21002FB06
J 0
(1650 -825);
DISPLAY 0.638298 (1650 -825);
DISPLAY INVISIBLE (1650 -825);
FORCEPROP 1 LAST MATERIAL CHIP
J 0
(2100 -875);
DISPLAY 0.638298 (2100 -875);
FORCEPROP 1 LAST TOLERANCE 1%
J 0
(2000 -875);
DISPLAY 0.638298 (2000 -875);
FORCEPROP 1 LAST VALUE 1K
J 2
(1975 -875);
DISPLAY 0.638298 (1975 -875);
FORCEPROP 1 LAST $LOCATION R1473
J 0
(1500 -875);
DISPLAY 0.638298 (1500 -875);
FORCEPROP 1 LASTPIN (1675 -875) $PN 1
J 0
(1687 -863);
DISPLAY 0.787234 (1687 -863);
FORCEPROP 1 LASTPIN (1875 -875) $PN 2
J 0
(1837 -863);
DISPLAY 0.787234 (1837 -863);
FORCEPROP 1 LAST WATTAGE 1/16W
J 2
(2050 -775);
DISPLAY 0.638298 (2050 -775);
DISPLAY INVISIBLE (2050 -775);
FORCEPROP 1 LAST PACK_TYPE 0402LF
J 0
(1650 -775);
DISPLAY 0.638298 (1650 -775);
DISPLAY INVISIBLE (1650 -775);
FORCEPROP 2 LAST CDS_LIB pure_quanta
J 0
(1775 -875);
PAINT MONO (1775 -875);
DISPLAY INVISIBLE (1775 -875);
FORCEPROP 1 LAST PATH I37
J 0
(1725 -725);
DISPLAY 0.978723 (1725 -725);
PAINT WHITE (1725 -725);
DISPLAY INVISIBLE (1725 -725);
FORCEPROP 2 LAST CDS_LOCATION R1473
J 0
(1725 -675);
DISPLAY 1.021277 (1725 -675);
DISPLAY INVISIBLE (1725 -675);
FORCEPROP 2 LAST $SEC 1
J 0
(1725 -675);
DISPLAY 0.680851 (1725 -675);
PAINT MONO (1725 -675);
DISPLAY INVISIBLE (1725 -675);
FORCEPROP 2 LAST CDS_SEC 1
J 0
(1725 -675);
DISPLAY 1.021277 (1725 -675);
DISPLAY INVISIBLE (1725 -675);
FORCEADD Q_RES..1
(1775 -775);
FORCEPROP 1 LAST PART_NUMBER CS21002FB06
J 0
(1650 -725);
DISPLAY 0.638298 (1650 -725);
DISPLAY INVISIBLE (1650 -725);
FORCEPROP 1 LAST VALUE 1K
J 2
(1975 -775);
DISPLAY 0.638298 (1975 -775);
FORCEPROP 1 LAST TOLERANCE 1%
J 0
(2000 -775);
DISPLAY 0.638298 (2000 -775);
FORCEPROP 1 LAST MATERIAL CHIP
J 0
(2100 -775);
DISPLAY 0.638298 (2100 -775);
FORCEPROP 1 LAST $LOCATION R1741
J 0
(1500 -775);
DISPLAY 0.638298 (1500 -775);
FORCEPROP 1 LASTPIN (1675 -775) $PN 1
J 0
(1687 -763);
DISPLAY 0.787234 (1687 -763);
FORCEPROP 1 LASTPIN (1875 -775) $PN 2
J 0
(1837 -763);
DISPLAY 0.787234 (1837 -763);
FORCEPROP 1 LAST WATTAGE 1/16W
J 2
(2050 -675);
DISPLAY 0.638298 (2050 -675);
DISPLAY INVISIBLE (2050 -675);
FORCEPROP 1 LAST PACK_TYPE 0402LF
J 0
(1650 -675);
DISPLAY 0.638298 (1650 -675);
DISPLAY INVISIBLE (1650 -675);
FORCEPROP 2 LAST CDS_LIB pure_quanta
J 0
(1775 -775);
PAINT MONO (1775 -775);
DISPLAY INVISIBLE (1775 -775);
FORCEPROP 1 LAST PATH I38
J 0
(1725 -625);
DISPLAY 0.978723 (1725 -625);
PAINT WHITE (1725 -625);
DISPLAY INVISIBLE (1725 -625);
FORCEPROP 2 LAST CDS_LOCATION R1741
J 0
(1725 -575);
DISPLAY 1.021277 (1725 -575);
DISPLAY INVISIBLE (1725 -575);
FORCEPROP 2 LAST $SEC 1
J 0
(1725 -575);
DISPLAY 0.680851 (1725 -575);
PAINT MONO (1725 -575);
DISPLAY INVISIBLE (1725 -575);
FORCEPROP 2 LAST CDS_SEC 1
J 0
(1725 -575);
DISPLAY 1.021277 (1725 -575);
DISPLAY INVISIBLE (1725 -575);
FORCEADD Q_RES..1
(1775 -475);
FORCEPROP 1 LAST PART_NUMBER CS31002FB08
J 0
(1650 -400);
DISPLAY 0.638298 (1650 -400);
DISPLAY INVISIBLE (1650 -400);
FORCEPROP 1 LAST VALUE 10K
J 2
(1975 -475);
DISPLAY 0.638298 (1975 -475);
FORCEPROP 1 LAST TOLERANCE 1%
J 0
(2000 -475);
DISPLAY 0.638298 (2000 -475);
FORCEPROP 1 LAST MATERIAL CHIP
J 0
(2100 -475);
DISPLAY 0.638298 (2100 -475);
FORCEPROP 1 LAST $LOCATION R2244
J 0
(1500 -475);
DISPLAY 0.638298 (1500 -475);
FORCEPROP 1 LASTPIN (1675 -475) $PN 1
J 0
(1687 -463);
DISPLAY 0.787234 (1687 -463);
PAINT MONO (1687 -463);
FORCEPROP 1 LASTPIN (1875 -475) $PN 2
J 0
(1837 -463);
DISPLAY 0.787234 (1837 -463);
PAINT MONO (1837 -463);
FORCEPROP 1 LAST PACK_TYPE 0402LF
J 0
(1650 -350);
DISPLAY 0.638298 (1650 -350);
DISPLAY INVISIBLE (1650 -350);
FORCEPROP 1 LAST WATTAGE 1/16W
J 2
(2025 -350);
DISPLAY 0.638298 (2025 -350);
DISPLAY INVISIBLE (2025 -350);
FORCEPROP 2 LAST CDS_LIB pure_quanta
J 0
(1775 -475);
DISPLAY INVISIBLE (1775 -475);
FORCEPROP 1 LAST PATH I39
J 0
(1725 -325);
DISPLAY 0.978723 (1725 -325);
PAINT WHITE (1725 -325);
DISPLAY INVISIBLE (1725 -325);
FORCEPROP 0 LAST CDS_LOCATION R2244
J 0
(2100 -425);
DISPLAY 1.021277 (2100 -425);
DISPLAY INVISIBLE (2100 -425);
FORCEPROP 0 LAST $SEC 1
J 0
(2100 -425);
DISPLAY 0.680851 (2100 -425);
PAINT MONO (2100 -425);
DISPLAY INVISIBLE (2100 -425);
FORCEPROP 0 LAST CDS_SEC 1
J 0
(2100 -425);
DISPLAY 1.021277 (2100 -425);
DISPLAY INVISIBLE (2100 -425);
FORCEADD Q_CAP..2
(-1525 -2475);
FORCEPROP 1 LAST PART_NUMBER CH11006JB00
J 1
(-1525 -2400);
DISPLAY 0.617021 (-1525 -2400);
PAINT BLUE (-1525 -2400);
DISPLAY INVISIBLE (-1525 -2400);
FORCEPROP 1 LAST VALUE 100PF
J 2
(-1250 -2475);
DISPLAY 0.617021 (-1250 -2475);
PAINT SKYBLUE (-1250 -2475);
FORCEPROP 1 LAST TOLERANCE 5%
J 2
(-1150 -2475);
DISPLAY 0.617021 (-1150 -2475);
PAINT SKYBLUE (-1150 -2475);
FORCEPROP 1 LAST LOCATION C1211
J 1
(-1750 -2475);
DISPLAY 0.617021 (-1750 -2475);
PAINT AQUA (-1750 -2475);
FORCEPROP 1 LASTPIN (-1625 -2475) $PN 1
J 0
(-1635 -2460);
DISPLAY 0.787234 (-1635 -2460);
PAINT MONO (-1635 -2460);
FORCEPROP 1 LASTPIN (-1425 -2475) $PN 2
J 0
(-1440 -2460);
DISPLAY 0.787234 (-1440 -2460);
PAINT MONO (-1440 -2460);
FORCEPROP 2 LAST CDS_LIB pure_quanta
J 0
(-1525 -2475);
DISPLAY INVISIBLE (-1525 -2475);
FORCEPROP 1 LAST MATERIAL NPO
J 0
(-1700 -2350);
DISPLAY 0.617021 (-1700 -2350);
PAINT SKYBLUE (-1700 -2350);
DISPLAY INVISIBLE (-1700 -2350);
FORCEPROP 1 LAST PACK_TYPE 0402
J 1
(-1500 -2350);
DISPLAY 0.617021 (-1500 -2350);
PAINT SKYBLUE (-1500 -2350);
DISPLAY INVISIBLE (-1500 -2350);
FORCEPROP 1 LAST VOLTAGE 50V
J 0
(-1400 -2350);
DISPLAY 0.617021 (-1400 -2350);
PAINT SKYBLUE (-1400 -2350);
DISPLAY INVISIBLE (-1400 -2350);
FORCEPROP 1 LAST PATH I4
J 0
(-1525 -2275);
DISPLAY 0.978723 (-1525 -2275);
PAINT WHITE (-1525 -2275);
DISPLAY INVISIBLE (-1525 -2275);
FORCEPROP 0 LAST $SEC 1
J 0
(-1150 -2425);
DISPLAY 0.680851 (-1150 -2425);
PAINT MONO (-1150 -2425);
DISPLAY INVISIBLE (-1150 -2425);
FORCEPROP 0 LAST CDS_SEC 1
J 0
(-1150 -2425);
DISPLAY 1.021277 (-1150 -2425);
DISPLAY INVISIBLE (-1150 -2425);
FORCEADD Q_RES..1
(1775 -350);
FORCEPROP 1 LAST PART_NUMBER CS31002FB08
J 0
(1650 -275);
DISPLAY 0.638298 (1650 -275);
DISPLAY INVISIBLE (1650 -275);
FORCEPROP 1 LAST VALUE 10K
J 2
(1975 -350);
DISPLAY 0.638298 (1975 -350);
FORCEPROP 1 LAST TOLERANCE 1%
J 0
(2000 -350);
DISPLAY 0.638298 (2000 -350);
FORCEPROP 1 LAST MATERIAL EMPTY
J 0
(2100 -350);
DISPLAY 0.638298 (2100 -350);
PAINT RED (2100 -350);
FORCEPROP 1 LAST $LOCATION R139
J 0
(1500 -350);
DISPLAY 0.638298 (1500 -350);
FORCEPROP 1 LASTPIN (1675 -350) $PN 1
J 0
(1687 -338);
DISPLAY 0.787234 (1687 -338);
FORCEPROP 1 LASTPIN (1875 -350) $PN 2
J 0
(1837 -338);
DISPLAY 0.787234 (1837 -338);
FORCEPROP 2 LAST CDS_LIB pure_quanta
J 0
(1775 -350);
PAINT MONO (1775 -350);
DISPLAY INVISIBLE (1775 -350);
FORCEPROP 1 LAST WATTAGE 1/16W
J 2
(2025 -225);
DISPLAY 0.638298 (2025 -225);
DISPLAY INVISIBLE (2025 -225);
FORCEPROP 1 LAST PACK_TYPE 0402LF
J 0
(1650 -225);
DISPLAY 0.638298 (1650 -225);
DISPLAY INVISIBLE (1650 -225);
FORCEPROP 1 LAST PATH I40
J 0
(1725 -200);
DISPLAY 0.978723 (1725 -200);
PAINT WHITE (1725 -200);
DISPLAY INVISIBLE (1725 -200);
FORCEPROP 2 LAST CDS_LOCATION R139
J 0
(1725 -150);
DISPLAY 1.021277 (1725 -150);
DISPLAY INVISIBLE (1725 -150);
FORCEPROP 2 LAST $SEC 1
J 0
(1725 -150);
DISPLAY 0.680851 (1725 -150);
PAINT MONO (1725 -150);
DISPLAY INVISIBLE (1725 -150);
FORCEPROP 2 LAST CDS_SEC 1
J 0
(1725 -150);
DISPLAY 1.021277 (1725 -150);
DISPLAY INVISIBLE (1725 -150);
FORCEADD Q_RES..1
(1775 -50);
FORCEPROP 1 LAST PART_NUMBER CS31002FB08
J 0
(1650 25);
DISPLAY 0.638298 (1650 25);
DISPLAY INVISIBLE (1650 25);
FORCEPROP 1 LAST MATERIAL EMPTY
J 0
(2100 -50);
DISPLAY 0.638298 (2100 -50);
PAINT RED (2100 -50);
FORCEPROP 1 LAST TOLERANCE 1%
J 0
(2000 -50);
DISPLAY 0.638298 (2000 -50);
FORCEPROP 1 LAST VALUE 10K
J 2
(1975 -50);
DISPLAY 0.638298 (1975 -50);
FORCEPROP 1 LAST $LOCATION R1440
J 0
(1500 -50);
DISPLAY 0.638298 (1500 -50);
FORCEPROP 1 LASTPIN (1675 -50) $PN 1
J 0
(1687 -38);
DISPLAY 0.787234 (1687 -38);
FORCEPROP 1 LASTPIN (1875 -50) $PN 2
J 0
(1837 -38);
DISPLAY 0.787234 (1837 -38);
FORCEPROP 2 LAST CDS_LIB pure_quanta
J 0
(1775 -50);
PAINT MONO (1775 -50);
DISPLAY INVISIBLE (1775 -50);
FORCEPROP 1 LAST WATTAGE 1/16W
J 2
(2025 75);
DISPLAY 0.638298 (2025 75);
DISPLAY INVISIBLE (2025 75);
FORCEPROP 1 LAST PACK_TYPE 0402LF
J 0
(1650 75);
DISPLAY 0.638298 (1650 75);
DISPLAY INVISIBLE (1650 75);
FORCEPROP 1 LAST PATH I41
J 0
(1725 100);
DISPLAY 0.978723 (1725 100);
PAINT WHITE (1725 100);
DISPLAY INVISIBLE (1725 100);
FORCEPROP 2 LAST CDS_LOCATION R1440
J 0
(1725 150);
DISPLAY 1.021277 (1725 150);
DISPLAY INVISIBLE (1725 150);
FORCEPROP 2 LAST $SEC 1
J 0
(1725 150);
DISPLAY 0.680851 (1725 150);
PAINT MONO (1725 150);
DISPLAY INVISIBLE (1725 150);
FORCEPROP 2 LAST CDS_SEC 1
J 0
(1725 150);
DISPLAY 1.021277 (1725 150);
DISPLAY INVISIBLE (1725 150);
FORCEADD Q_RES..1
(1775 400);
FORCEPROP 1 LAST PART_NUMBER CS31002FB08
J 0
(1650 475);
DISPLAY 0.638298 (1650 475);
DISPLAY INVISIBLE (1650 475);
FORCEPROP 1 LAST TOLERANCE 1%
J 0
(2000 400);
DISPLAY 0.638298 (2000 400);
FORCEPROP 1 LAST MATERIAL CHIP
J 0
(2100 400);
DISPLAY 0.638298 (2100 400);
FORCEPROP 1 LAST VALUE 10K
J 2
(1975 400);
DISPLAY 0.638298 (1975 400);
FORCEPROP 1 LAST $LOCATION R1437
J 0
(1500 400);
DISPLAY 0.638298 (1500 400);
FORCEPROP 1 LASTPIN (1675 400) $PN 1
J 0
(1687 412);
DISPLAY 0.787234 (1687 412);
FORCEPROP 1 LASTPIN (1875 400) $PN 2
J 0
(1837 412);
DISPLAY 0.787234 (1837 412);
FORCEPROP 1 LAST PACK_TYPE 0402LF
J 0
(1650 525);
DISPLAY 0.638298 (1650 525);
DISPLAY INVISIBLE (1650 525);
FORCEPROP 1 LAST WATTAGE 1/16W
J 2
(2025 525);
DISPLAY 0.638298 (2025 525);
DISPLAY INVISIBLE (2025 525);
FORCEPROP 2 LAST CDS_LIB pure_quanta
J 0
(1775 400);
PAINT MONO (1775 400);
DISPLAY INVISIBLE (1775 400);
FORCEPROP 1 LAST PATH I42
J 0
(1725 550);
DISPLAY 0.978723 (1725 550);
PAINT WHITE (1725 550);
DISPLAY INVISIBLE (1725 550);
FORCEPROP 2 LAST CDS_LOCATION R1437
J 0
(1725 600);
DISPLAY 1.021277 (1725 600);
DISPLAY INVISIBLE (1725 600);
FORCEPROP 2 LAST $SEC 1
J 0
(1725 600);
DISPLAY 0.680851 (1725 600);
PAINT MONO (1725 600);
DISPLAY INVISIBLE (1725 600);
FORCEPROP 2 LAST CDS_SEC 1
J 0
(1725 600);
DISPLAY 1.021277 (1725 600);
DISPLAY INVISIBLE (1725 600);
FORCEADD Q_RES..1
(1775 700);
FORCEPROP 1 LAST PART_NUMBER CS31002FB08
J 0
(1650 775);
DISPLAY 0.638298 (1650 775);
DISPLAY INVISIBLE (1650 775);
FORCEPROP 1 LAST VALUE 10K
J 2
(1975 700);
DISPLAY 0.638298 (1975 700);
FORCEPROP 1 LAST TOLERANCE 1%
J 0
(2000 700);
DISPLAY 0.638298 (2000 700);
FORCEPROP 1 LAST MATERIAL CHIP
J 0
(2100 700);
DISPLAY 0.638298 (2100 700);
FORCEPROP 1 LAST $LOCATION R1435
J 0
(1500 700);
DISPLAY 0.638298 (1500 700);
FORCEPROP 1 LASTPIN (1675 700) $PN 1
J 0
(1687 712);
DISPLAY 0.787234 (1687 712);
FORCEPROP 1 LASTPIN (1875 700) $PN 2
J 0
(1837 712);
DISPLAY 0.787234 (1837 712);
FORCEPROP 2 LAST CDS_LIB pure_quanta
J 0
(1775 700);
PAINT MONO (1775 700);
DISPLAY INVISIBLE (1775 700);
FORCEPROP 1 LAST WATTAGE 1/16W
J 2
(2025 825);
DISPLAY 0.638298 (2025 825);
DISPLAY INVISIBLE (2025 825);
FORCEPROP 1 LAST PACK_TYPE 0402LF
J 0
(1650 825);
DISPLAY 0.638298 (1650 825);
DISPLAY INVISIBLE (1650 825);
FORCEPROP 1 LAST PATH I43
J 0
(1725 850);
DISPLAY 0.978723 (1725 850);
PAINT WHITE (1725 850);
DISPLAY INVISIBLE (1725 850);
FORCEPROP 2 LAST CDS_LOCATION R1435
J 0
(1725 900);
DISPLAY 1.021277 (1725 900);
DISPLAY INVISIBLE (1725 900);
FORCEPROP 2 LAST $SEC 1
J 0
(1725 900);
DISPLAY 0.680851 (1725 900);
PAINT MONO (1725 900);
DISPLAY INVISIBLE (1725 900);
FORCEPROP 2 LAST CDS_SEC 1
J 0
(1725 900);
DISPLAY 1.021277 (1725 900);
DISPLAY INVISIBLE (1725 900);
FORCEADD Q_RES..1
(1775 850);
FORCEPROP 1 LAST PART_NUMBER CS31002FB08
J 0
(1650 925);
DISPLAY 0.638298 (1650 925);
DISPLAY INVISIBLE (1650 925);
FORCEPROP 1 LAST WATTAGE 1/16W
J 2
(2025 975);
DISPLAY 0.638298 (2025 975);
FORCEPROP 1 LAST VALUE 10K
J 2
(1975 850);
DISPLAY 0.638298 (1975 850);
FORCEPROP 1 LAST MATERIAL CHIP
J 0
(2100 850);
DISPLAY 0.638298 (2100 850);
FORCEPROP 1 LAST TOLERANCE 1%
J 0
(2000 850);
DISPLAY 0.638298 (2000 850);
FORCEPROP 1 LAST PACK_TYPE 0402LF
J 0
(1650 975);
DISPLAY 0.638298 (1650 975);
FORCEPROP 1 LAST $LOCATION R1434
J 0
(1500 850);
DISPLAY 0.638298 (1500 850);
FORCEPROP 1 LASTPIN (1675 850) $PN 1
J 0
(1687 862);
DISPLAY 0.787234 (1687 862);
FORCEPROP 1 LASTPIN (1875 850) $PN 2
J 0
(1837 862);
DISPLAY 0.787234 (1837 862);
FORCEPROP 2 LAST CDS_LIB pure_quanta
J 0
(1775 850);
PAINT MONO (1775 850);
DISPLAY INVISIBLE (1775 850);
FORCEPROP 1 LAST PATH I44
J 0
(1725 1000);
DISPLAY 0.978723 (1725 1000);
PAINT WHITE (1725 1000);
DISPLAY INVISIBLE (1725 1000);
FORCEPROP 2 LAST CDS_LOCATION R1434
J 0
(1725 1050);
DISPLAY 1.021277 (1725 1050);
DISPLAY INVISIBLE (1725 1050);
FORCEPROP 2 LAST $SEC 1
J 0
(1725 1050);
DISPLAY 0.680851 (1725 1050);
PAINT MONO (1725 1050);
DISPLAY INVISIBLE (1725 1050);
FORCEPROP 2 LAST CDS_SEC 1
J 0
(1725 1050);
DISPLAY 1.021277 (1725 1050);
DISPLAY INVISIBLE (1725 1050);
FORCEADD UNIVERSAL_POWER..1
(2325 1075);
FORCEPROP 3 LASTPIN (2325 1025) SIG_NAME P3V3_AUX\g
J 0
(2335 1035);
DISPLAY 0.659574 (2335 1035);
PAINT MONO (2335 1035);
DISPLAY INVISIBLE (2335 1035);
FORCEPROP 1 LAST HDL_POWER P3V3_AUX
J 1
(2325 1125);
DISPLAY 0.872340 (2325 1125);
PAINT GREEN (2325 1125);
FORCEPROP 2 LAST CDS_LIB logical_power
J 0
(2325 1075);
PAINT MONO (2325 1075);
DISPLAY INVISIBLE (2325 1075);
FORCEPROP 1 LAST PATH I45
J 0
(2375 1100);
DISPLAY 0.872340 (2375 1100);
PAINT AQUA (2375 1100);
DISPLAY INVISIBLE (2375 1100);
FORCEADD Q_RES..2
(-2325 -850);
FORCEPROP 1 LAST PART_NUMBER CS31002FB08
J 0
(-2285 -975);
DISPLAY 0.978723 (-2285 -975);
DISPLAY INVISIBLE (-2285 -975);
FORCEPROP 1 LAST PACK_TYPE 0402LF
J 0
(-2285 -1025);
DISPLAY 0.978723 (-2285 -1025);
FORCEPROP 1 LAST MATERIAL CHIP
J 0
(-2285 -925);
DISPLAY 0.978723 (-2285 -925);
FORCEPROP 1 LAST WATTAGE 1/16W
J 0
(-2285 -875);
DISPLAY 0.978723 (-2285 -875);
FORCEPROP 1 LAST TOLERANCE 1%
J 0
(-2280 -825);
DISPLAY 0.978723 (-2280 -825);
FORCEPROP 1 LAST VALUE 10K
J 0
(-2280 -775);
DISPLAY 0.978723 (-2280 -775);
FORCEPROP 1 LAST $LOCATION R4674
J 0
(-2280 -725);
DISPLAY 0.978723 (-2280 -725);
FORCEPROP 1 LASTPIN (-2325 -750) $PN 1
J 0
(-2320 -788);
DISPLAY 0.787234 (-2320 -788);
PAINT MONO (-2320 -788);
FORCEPROP 1 LASTPIN (-2325 -950) $PN 2
J 0
(-2320 -940);
DISPLAY 0.787234 (-2320 -940);
PAINT MONO (-2320 -940);
FORCEPROP 2 LAST CDS_LIB pure_quanta
J 0
(-2325 -850);
DISPLAY INVISIBLE (-2325 -850);
FORCEPROP 1 LAST PATH I46
J 0
(-2275 -675);
DISPLAY 0.978723 (-2275 -675);
PAINT WHITE (-2275 -675);
DISPLAY INVISIBLE (-2275 -675);
FORCEPROP 0 LAST CDS_LOCATION R4674
J 0
(-2275 -675);
DISPLAY 1.021277 (-2275 -675);
DISPLAY INVISIBLE (-2275 -675);
FORCEPROP 0 LAST $SEC 1
J 0
(-2275 -675);
DISPLAY 0.680851 (-2275 -675);
PAINT MONO (-2275 -675);
DISPLAY INVISIBLE (-2275 -675);
FORCEPROP 0 LAST CDS_SEC 1
J 0
(-2275 -675);
DISPLAY 1.021277 (-2275 -675);
DISPLAY INVISIBLE (-2275 -675);
FORCEADD UNIVERSAL_GND..1
(-2325 -1050);
FORCEPROP 3 LASTPIN (-2325 -1000) SIG_NAME GND\g
J 0
(-2315 -990);
DISPLAY 0.659574 (-2315 -990);
PAINT MONO (-2315 -990);
DISPLAY INVISIBLE (-2315 -990);
FORCEPROP 2 LAST ROOM IO_SLOT
J 1
(-2550 -975);
DISPLAY 0.744681 (-2550 -975);
DISPLAY INVISIBLE (-2550 -975);
FORCEPROP 2 LAST CDS_LIB logical_power
J 0
(-2325 -1050);
DISPLAY INVISIBLE (-2325 -1050);
FORCEPROP 1 LAST HDL_POWER GND
J 1
(-2300 -1125);
DISPLAY 0.872340 (-2300 -1125);
PAINT GREEN (-2300 -1125);
DISPLAY INVISIBLE (-2300 -1125);
FORCEPROP 1 LAST PATH I47
J 0
(-2250 -1050);
DISPLAY 0.872340 (-2250 -1050);
PAINT AQUA (-2250 -1050);
DISPLAY INVISIBLE (-2250 -1050);
FORCEADD UNIVERSAL_GND..1
(-975 -2975);
FORCEPROP 3 LASTPIN (-975 -2925) SIG_NAME GND\g
J 0
(-965 -2915);
DISPLAY 0.659574 (-965 -2915);
PAINT MONO (-965 -2915);
DISPLAY INVISIBLE (-965 -2915);
FORCEPROP 2 LAST ROOM IO_SLOT
J 1
(-1200 -2900);
DISPLAY 0.744681 (-1200 -2900);
DISPLAY INVISIBLE (-1200 -2900);
FORCEPROP 2 LAST CDS_LIB logical_power
J 0
(-975 -2975);
PAINT MONO (-975 -2975);
DISPLAY INVISIBLE (-975 -2975);
FORCEPROP 1 LAST HDL_POWER GND
J 1
(-950 -3050);
DISPLAY 0.872340 (-950 -3050);
PAINT GREEN (-950 -3050);
DISPLAY INVISIBLE (-950 -3050);
FORCEPROP 1 LAST PATH I5
J 0
(-900 -2975);
DISPLAY 0.872340 (-900 -2975);
PAINT AQUA (-900 -2975);
DISPLAY INVISIBLE (-900 -2975);
FORCEADD OFFPAGE..1
(-3500 -500);
FORCEPROP 2 LAST $XR1 213 
J 0
(-3902 -500);
DISPLAY 0.638298 (-3902 -500);
PAINT MONO (-3902 -500);
FORCEPROP 2 LAST $XR0 182 
J 0
(-3782 -500);
DISPLAY 0.638298 (-3782 -500);
PAINT MONO (-3782 -500);
FORCEPROP 2 LAST CDS_LIB standard
J 0
(-3500 -500);
PAINT MONO (-3500 -500);
DISPLAY INVISIBLE (-3500 -500);
FORCEPROP 1 LAST OFFPAGE TRUE
J 0
(-3175 -625);
DISPLAY 0.872340 (-3175 -625);
PAINT GREEN (-3175 -625);
DISPLAY INVISIBLE (-3175 -625);
FORCEPROP 1 LAST COMMENT_BODY TRUE
J 0
(-3375 -600);
DISPLAY 0.872340 (-3375 -600);
PAINT GREEN (-3375 -600);
DISPLAY INVISIBLE (-3375 -600);
FORCEPROP 2 LAST PATH I6
J 0
(-3775 -450);
DISPLAY 1.021277 (-3775 -450);
DISPLAY INVISIBLE (-3775 -450);
FORCEADD OFFPAGE..1
(-3500 -150);
FORCEPROP 2 LAST $XR1 218 
J 0
(-3902 -150);
DISPLAY 0.638298 (-3902 -150);
PAINT MONO (-3902 -150);
FORCEPROP 2 LAST $XR0 215 
J 0
(-3782 -150);
DISPLAY 0.638298 (-3782 -150);
PAINT MONO (-3782 -150);
FORCEPROP 2 LAST CDS_LIB standard
J 0
(-3500 -150);
PAINT MONO (-3500 -150);
DISPLAY INVISIBLE (-3500 -150);
FORCEPROP 1 LAST OFFPAGE TRUE
J 0
(-3175 -275);
DISPLAY 0.872340 (-3175 -275);
PAINT GREEN (-3175 -275);
DISPLAY INVISIBLE (-3175 -275);
FORCEPROP 1 LAST COMMENT_BODY TRUE
J 0
(-3375 -250);
DISPLAY 0.872340 (-3375 -250);
PAINT GREEN (-3375 -250);
DISPLAY INVISIBLE (-3375 -250);
FORCEPROP 2 LAST PATH I7
J 0
(-3775 -100);
DISPLAY 1.021277 (-3775 -100);
DISPLAY INVISIBLE (-3775 -100);
FORCEADD OFFPAGE..1
(-3500 875);
FORCEPROP 2 LAST $XR0 213 
J 0
(-3782 875);
DISPLAY 0.638298 (-3782 875);
PAINT MONO (-3782 875);
FORCEPROP 2 LAST CDS_LIB standard
J 0
(-3500 875);
PAINT MONO (-3500 875);
DISPLAY INVISIBLE (-3500 875);
FORCEPROP 1 LAST OFFPAGE TRUE
J 0
(-3175 750);
DISPLAY 0.872340 (-3175 750);
PAINT GREEN (-3175 750);
DISPLAY INVISIBLE (-3175 750);
FORCEPROP 1 LAST COMMENT_BODY TRUE
J 0
(-3375 775);
DISPLAY 0.872340 (-3375 775);
PAINT GREEN (-3375 775);
DISPLAY INVISIBLE (-3375 775);
FORCEPROP 2 LAST PATH I8
J 0
(-3775 925);
DISPLAY 1.021277 (-3775 925);
DISPLAY INVISIBLE (-3775 925);
FORCEADD OFFPAGE..1
(-3500 1175);
FORCEPROP 2 LAST $XR1 244 
J 0
(-3902 1175);
DISPLAY 0.638298 (-3902 1175);
PAINT MONO (-3902 1175);
FORCEPROP 2 LAST $XR0 214 
J 0
(-3782 1175);
DISPLAY 0.638298 (-3782 1175);
PAINT MONO (-3782 1175);
FORCEPROP 2 LAST CDS_LIB standard
J 0
(-3500 1175);
PAINT MONO (-3500 1175);
DISPLAY INVISIBLE (-3500 1175);
FORCEPROP 1 LAST OFFPAGE TRUE
J 0
(-3175 1050);
DISPLAY 0.872340 (-3175 1050);
PAINT GREEN (-3175 1050);
DISPLAY INVISIBLE (-3175 1050);
FORCEPROP 1 LAST COMMENT_BODY TRUE
J 0
(-3375 1075);
DISPLAY 0.872340 (-3375 1075);
PAINT GREEN (-3375 1075);
DISPLAY INVISIBLE (-3375 1075);
FORCEPROP 2 LAST PATH I9
J 0
(-3775 1225);
DISPLAY 1.021277 (-3775 1225);
DISPLAY INVISIBLE (-3775 1225);
FORCEADD QUANTA_TITLE_BLOCK_C..1
(4775 -3375);
FORCEPROP 0 LAST CDS_CON_LAST_MODIFIED Fri Aug 25 14:03:41 2023
J 0
(2890 -3360);
PAINT MONO (2890 -3360);
DISPLAY INVISIBLE (2890 -3360);
FORCEPROP 2 LAST CUSTOM_TXT_CDS <XR_PAGE_TITLE>
J 0
(-3115 1875);
DISPLAY 0.638298 (-3115 1875);
PAINT PINK (-3115 1875);
DISPLAY INVISIBLE (-3115 1875);
FORCEPROP 2 LAST CUSTOM_TXT_CDS <CON_LAST_MODIFIED>
J 0
(2890 -3360);
DISPLAY 0.978723 (2890 -3360);
FORCEPROP 2 LAST CUSTOM_TXT_CDS <NAME_2>
J 0
(1600 -3325);
FORCEPROP 2 LAST CUSTOM_TXT_CDS <Q_PROJ>
J 0
(2393 -3273);
DISPLAY 1.212766 (2393 -3273);
FORCEPROP 2 LAST CUSTOM_TXT_CDS <CON_PAGE_NUM> OF <CON_TOTAL_PAGES>
J 0
(4329 -3357);
DISPLAY 0.978723 (4329 -3357);
FORCEPROP 2 LAST CUSTOM_TXT_CDS <Q_REV>
J 0
(4591 -3272);
DISPLAY 1.212766 (4591 -3272);
FORCEPROP 2 LAST CUSTOM_TXT_CDS <Q_NUMBER>
J 0
(3372 -3272);
DISPLAY 1.212766 (3372 -3272);
FORCEPROP 2 LAST CUSTOM_TXT_CDS <NAME_1>
J 0
(1600 -3200);
FORCEPROP 1 LAST Q_TITLE MAIN FPGA / PFR - MISC/PU/PD
J 0
(-4491 -3374);
DISPLAY 2.446809 (-4491 -3374);
PAINT GREEN (-4491 -3374);
FORCEPROP 1 LAST Q_DEPT 
J 1
(1012 -3326);
DISPLAY 1.957447 (1012 -3326);
PAINT GREEN (1012 -3326);
FORCEPROP 2 LAST CDS_XR_PAGE_TITLE CR-220 : @S9S_MB_2U_LIB.S9S_MB_2U(SCH_1):PAGE220
J 0
(-3115 1875);
DISPLAY 0.638298 (-3115 1875);
PAINT PINK (-3115 1875);
DISPLAY INVISIBLE (-3115 1875);
FORCEPROP 1 LAST COMMENT_BODY TRUE
J 0
(4787 -3388);
DISPLAY 0.978723 (4787 -3388);
PAINT GREEN (4787 -3388);
DISPLAY INVISIBLE (4787 -3388);
FORCEPROP 2 LAST PAGE_BORDER TRUE
J 0
(-3115 1875);
DISPLAY 0.638298 (-3115 1875);
PAINT PINK (-3115 1875);
DISPLAY INVISIBLE (-3115 1875);
FORCEPROP 1 LAST CDS_LMAN_SYM_OUTLINE -9475,6775,100,-125
J 0
(4775 -3375);
DISPLAY 0.468085 (4775 -3375);
PAINT GREEN (4775 -3375);
DISPLAY INVISIBLE (4775 -3375);
FORCEPROP 2 LAST CDS_LIB pure_quanta
J 0
(4775 -3375);
PAINT MONO (4775 -3375);
DISPLAY INVISIBLE (4775 -3375);
FORCEADD DNS..2
(1800 -1825);
PAINT RED (1800 -1825);
FORCEPROP 2 LAST CDS_LIB mstr_misc
J 0
(1800 -1825);
PAINT MONO (1800 -1825);
DISPLAY INVISIBLE (1800 -1825);
FORCEPROP 1 LAST COMMENT_BODY TRUE
J 0
(1800 -1825);
DISPLAY INVISIBLE (1800 -1825);
FORCEADD DNS..2
(-1825 -475);
PAINT RED (-1825 -475);
FORCEPROP 2 LAST CDS_LIB mstr_misc
J 0
(-1825 -475);
DISPLAY INVISIBLE (-1825 -475);
FORCEPROP 1 LAST COMMENT_BODY TRUE
J 0
(-1825 -475);
DISPLAY INVISIBLE (-1825 -475);
FORCEADD DNS..2
(-1825 -150);
PAINT RED (-1825 -150);
FORCEPROP 2 LAST CDS_LIB mstr_misc
J 0
(-1825 -150);
DISPLAY INVISIBLE (-1825 -150);
FORCEPROP 1 LAST COMMENT_BODY TRUE
J 0
(-1825 -150);
DISPLAY INVISIBLE (-1825 -150);
FORCEADD CAD_NOTE..1
(-3425 -1950);
FORCEPROP 0 LAST S1 PLACE THE 100PF CAPS FOR SI AND CLOSE TO MAIN PLD
J 0
(-3550 -2075);
DISPLAY 1.021277 (-3550 -2075);
PAINT YELLOW (-3550 -2075);
FORCEPROP 2 LAST CDS_LIB logical_power
J 0
(-3425 -1950);
PAINT MONO (-3425 -1950);
DISPLAY INVISIBLE (-3425 -1950);
FORCEPROP 1 LAST COMMENT_BODY TRUE
J 0
(-3400 -1850);
DISPLAY 0.978723 (-3400 -1850);
DISPLAY INVISIBLE (-3400 -1850);
FORCEADD DNS..2
(-3320 2020);
PAINT RED (-3320 2020);
FORCEPROP 2 LAST CDS_LIB mstr_misc
J 0
(-3320 2020);
PAINT MONO (-3320 2020);
DISPLAY INVISIBLE (-3320 2020);
FORCEPROP 1 LAST COMMENT_BODY TRUE
J 0
(-3320 2020);
DISPLAY INVISIBLE (-3320 2020);
FORCEADD DNS..2
(1800 -1725);
PAINT RED (1800 -1725);
FORCEPROP 2 LAST CDS_LIB mstr_misc
J 0
(1800 -1725);
DISPLAY INVISIBLE (1800 -1725);
FORCEPROP 1 LAST COMMENT_BODY TRUE
J 0
(1800 -1725);
DISPLAY INVISIBLE (1800 -1725);
FORCEADD DNS..2
(1800 -1625);
PAINT RED (1800 -1625);
FORCEPROP 2 LAST CDS_LIB mstr_misc
J 0
(1800 -1625);
DISPLAY INVISIBLE (1800 -1625);
FORCEPROP 1 LAST COMMENT_BODY TRUE
J 0
(1800 -1625);
DISPLAY INVISIBLE (1800 -1625);
FORCEADD DNS..2
(1800 -1525);
PAINT RED (1800 -1525);
FORCEPROP 2 LAST CDS_LIB mstr_misc
J 0
(1800 -1525);
DISPLAY INVISIBLE (1800 -1525);
FORCEPROP 1 LAST COMMENT_BODY TRUE
J 0
(1800 -1525);
DISPLAY INVISIBLE (1800 -1525);
FORCEADD DNS..2
(1800 -350);
PAINT RED (1800 -350);
FORCEPROP 2 LAST CDS_LIB mstr_misc
J 0
(1800 -350);
DISPLAY INVISIBLE (1800 -350);
FORCEPROP 1 LAST COMMENT_BODY TRUE
J 0
(1800 -350);
DISPLAY INVISIBLE (1800 -350);
FORCEADD DNS..2
(1780 -55);
PAINT RED (1780 -55);
FORCEPROP 2 LAST CDS_LIB mstr_misc
J 0
(1780 -55);
PAINT MONO (1780 -55);
DISPLAY INVISIBLE (1780 -55);
FORCEPROP 1 LAST COMMENT_BODY TRUE
J 0
(1780 -55);
DISPLAY INVISIBLE (1780 -55);
WIRE 16 -1 (2325 850)(2325 1025);
WIRE 16 -1 (2325 700)(2325 850);
WIRE 16 -1 (1875 850)(2325 850);
WIRE 16 -1 (-1300 1650)(-1300 1175);
WIRE 16 -1 (-3325 2625)(-3325 2725);
WIRE 16 -1 (2325 -1825)(2325 -2800);
WIRE 16 -1 (2325 -1825)(2325 -1725);
WIRE 16 -1 (1875 -1825)(2325 -1825);
WIRE 16 -1 (-3325 1875)(-3325 1950);
WIRE 16 -1 (-975 -2475)(-975 -2925);
WIRE 16 -1 (-975 -2475)(-975 -2325);
WIRE 16 -1 (-975 -2475)(-1425 -2475);
WIRE 16 -1 (-2325 -950)(-2325 -1000);
WIRE 16 -1 (-1300 1175)(-1750 1175);
WIRE 16 -1 (-1300 875)(-1750 875);
WIRE 16 -1 (-1300 875)(-1300 1175);
WIRE 16 -1 (-1300 -150)(-1750 -150);
WIRE 16 -1 (-1300 875)(-1300 -150);
WIRE 16 -1 (-1300 -150)(-1300 -350);
WIRE 16 2175 (-2425 -350)(-1300 -350);
WIRE 16 -1 (-1300 -500)(-1750 -500);
WIRE 16 -1 (-1300 -350)(-1300 -500);
WIRE 16 2175 (-1300 -500)(-1300 -1075);
WIRE 16 2175 (-2425 -350)(-2425 -1075);
WIRE 16 2175 (-2425 -1075)(-1300 -1075);
WIRE 16 2175 (1475 -1750)(2250 -1750);
WIRE 16 2175 (2250 -1750)(2250 -1925);
WIRE 16 2175 (1475 -1750)(1475 -1925);
WIRE 16 2175 (1475 -1925)(2250 -1925);
WIRE 16 -1 (1875 -1725)(2325 -1725);
WIRE 16 -1 (1875 -1625)(2325 -1625);
WIRE 16 -1 (2325 -1725)(2325 -1625);
WIRE 16 -1 (2325 -1625)(2325 -1525);
WIRE 16 -1 (1875 -1525)(2325 -1525);
WIRE 16 -1 (2325 -1075)(1875 -1075);
WIRE 16 -1 (1875 -975)(2325 -975);
WIRE 16 -1 (2325 -975)(2325 -1075);
WIRE 16 -1 (2325 -875)(1875 -875);
WIRE 16 -1 (2325 -975)(2325 -875);
WIRE 16 -1 (2325 -775)(1875 -775);
WIRE 16 -1 (2325 -775)(2325 -875);
WIRE 16 -1 (2325 -475)(1875 -475);
WIRE 16 -1 (2325 -475)(2325 -775);
WIRE 16 -1 (2325 -350)(1875 -350);
WIRE 16 -1 (2325 -350)(2325 -475);
WIRE 16 -1 (2325 -50)(1875 -50);
WIRE 16 -1 (2325 -350)(2325 -50);
WIRE 16 -1 (2325 -50)(2325 400);
WIRE 16 -1 (2325 400)(1875 400);
WIRE 16 -1 (2325 700)(1875 700);
WIRE 16 -1 (2325 700)(2325 400);
WIRE 16 2175 (1475 -1200)(2250 -1200);
WIRE 16 2175 (2250 -1025)(2250 -1200);
WIRE 16 2175 (1475 -1025)(1475 -1200);
WIRE 16 2175 (1475 -1025)(2250 -1025);
WIRE 16 -1 (-975 -2325)(-1425 -2325);
WIRE 16 -1 (-2325 -500)(-3450 -500);
FORCEPROP 0 LAST CDS_PHYS_NET_NAME FM_SLP_SUS_RSM_RST_N
J 0
(-3150 -458);
PAINT MONO (-3150 -458);
DISPLAY INVISIBLE (-3150 -458);
FORCEPROP 0 LAST SIG_NAME FM_SLP_SUS_RSM_RST_N
J 0
(-3225 -490);
DISPLAY 0.680851 (-3225 -490);
PAINT WHITE (-3225 -490);
WIRE 16 -1 (-2325 -750)(-2325 -500);
WIRE 16 -1 (-1950 -500)(-2325 -500);
WIRE 16 -1 (1225 -1825)(1675 -1825);
WIRE 16 -1 (175 -1175)(1225 -1175);
FORCEPROP 0 LAST SIG_NAME FM_DIS_PS_PWROK_DLY
J 0
(300 -1165);
DISPLAY 0.680851 (300 -1165);
PAINT WHITE (300 -1165);
WIRE 16 -1 (1225 -1825)(1225 -1175);
WIRE 16 -1 (1225 -1075)(1225 -1175);
WIRE 16 -1 (1675 -1075)(1225 -1075);
WIRE 16 -1 (1150 -1725)(1675 -1725);
WIRE 16 -1 (175 -1075)(1150 -1075);
FORCEPROP 0 LAST CDS_PHYS_NET_NAME FM_RST_PERST_BIT2
J 0
(200 -1033);
PAINT MONO (200 -1033);
DISPLAY INVISIBLE (200 -1033);
FORCEPROP 0 LAST SIG_NAME FM_RST_PERST_BIT2
J 0
(300 -1065);
DISPLAY 0.680851 (300 -1065);
PAINT WHITE (300 -1065);
WIRE 16 -1 (1150 -1725)(1150 -1075);
WIRE 16 -1 (1150 -975)(1150 -1075);
WIRE 16 -1 (1150 -975)(1675 -975);
WIRE 16 -1 (1675 -1625)(1075 -1625);
WIRE 16 -1 (175 -975)(1075 -975);
FORCEPROP 0 LAST CDS_PHYS_NET_NAME FM_RST_PERST_BIT1
J 0
(200 -933);
PAINT MONO (200 -933);
DISPLAY INVISIBLE (200 -933);
FORCEPROP 0 LAST SIG_NAME FM_RST_PERST_BIT1
J 0
(300 -965);
DISPLAY 0.680851 (300 -965);
PAINT WHITE (300 -965);
WIRE 16 -1 (1075 -1625)(1075 -975);
WIRE 16 -1 (1075 -875)(1075 -975);
WIRE 16 -1 (1075 -875)(1675 -875);
WIRE 16 -1 (1675 -1525)(1000 -1525);
WIRE 16 -1 (1000 -1525)(1000 -875);
WIRE 16 -1 (175 -875)(1000 -875);
FORCEPROP 0 LAST CDS_PHYS_NET_NAME FM_RST_PERST_BIT0
J 0
(200 -833);
PAINT MONO (200 -833);
DISPLAY INVISIBLE (200 -833);
FORCEPROP 0 LAST SIG_NAME FM_RST_PERST_BIT0
J 0
(300 -865);
DISPLAY 0.680851 (300 -865);
PAINT WHITE (300 -865);
WIRE 16 -1 (1000 -875)(1000 -775);
WIRE 16 -1 (1675 -775)(1000 -775);
WIRE 16 -1 (-1950 875)(-3450 875);
FORCEPROP 0 LAST CDS_PHYS_NET_NAME PU_MAIN_FPGA_CONFIG_DONE
J 0
(-3310 925);
PAINT MONO (-3310 925);
DISPLAY INVISIBLE (-3310 925);
FORCEPROP 0 LAST SIG_NAME PU_MAIN_FPGA_CONFIG_DONE
J 0
(-3225 885);
DISPLAY 0.680851 (-3225 885);
PAINT WHITE (-3225 885);
WIRE 16 -1 (175 400)(1675 400);
FORCEPROP 0 LAST CDS_PHYS_NET_NAME FM_PLD_HEARTBEAT_LVC3
J 0
(315 450);
PAINT MONO (315 450);
DISPLAY INVISIBLE (315 450);
FORCEPROP 2 LAST SIG_NAME FM_PLD_HEARTBEAT_LVC3
J 0
(300 410);
DISPLAY 0.851064 (300 410);
PAINT WHITE (300 410);
WIRE 16 -1 (175 -475)(1675 -475);
FORCEPROP 0 LAST CDS_PHYS_NET_NAME ROT_P1_RST_IND_N_R
J 0
(315 -425);
PAINT MONO (315 -425);
DISPLAY INVISIBLE (315 -425);
FORCEPROP 2 LAST SIG_NAME ROT_P1_RST_IND_N_R
J 0
(300 -465);
DISPLAY 0.851064 (300 -465);
PAINT WHITE (300 -465);
WIRE 16 -1 (-3375 -2475)(-1625 -2475);
FORCEPROP 0 LAST CDS_PHYS_NET_NAME PWRGD_PCH_PWROK_R
J 0
(-3235 -2425);
PAINT MONO (-3235 -2425);
DISPLAY INVISIBLE (-3235 -2425);
FORCEPROP 2 LAST SIG_NAME PWRGD_PCH_PWROK_R
J 0
(-3235 -2465);
DISPLAY 0.851064 (-3235 -2465);
PAINT WHITE (-3235 -2465);
WIRE 16 -1 (-1950 -150)(-3450 -150);
FORCEPROP 0 LAST CDS_PHYS_NET_NAME FM_CPU_RMCA_CATERR_LVT3_R_N
J 0
(-3150 -108);
PAINT MONO (-3150 -108);
DISPLAY INVISIBLE (-3150 -108);
FORCEPROP 0 LAST SIG_NAME FM_CPU_RMCA_CATERR_LVT3_R_N
J 0
(-3225 -140);
DISPLAY 0.680851 (-3225 -140);
PAINT WHITE (-3225 -140);
WIRE 16 -1 (175 850)(1675 850);
FORCEPROP 0 LAST CDS_PHYS_NET_NAME FM_SYS_THROTTLE_R_N
J 0
(315 900);
PAINT MONO (315 900);
DISPLAY INVISIBLE (315 900);
FORCEPROP 2 LAST SIG_NAME FM_SYS_THROTTLE_R_N
J 0
(300 860);
DISPLAY 0.851064 (300 860);
PAINT WHITE (300 860);
WIRE 16 -1 (175 -350)(1675 -350);
FORCEPROP 0 LAST CDS_PHYS_NET_NAME FM_BMC_PWRBTN_N
J 0
(315 -300);
PAINT MONO (315 -300);
DISPLAY INVISIBLE (315 -300);
FORCEPROP 2 LAST SIG_NAME FM_BMC_PWRBTN_N
J 0
(300 -340);
DISPLAY 0.851064 (300 -340);
PAINT WHITE (300 -340);
WIRE 16 -1 (175 700)(1675 700);
FORCEPROP 0 LAST CDS_PHYS_NET_NAME FM_ADR_TRIGGER_N
J 0
(315 750);
PAINT MONO (315 750);
DISPLAY INVISIBLE (315 750);
FORCEPROP 2 LAST SIG_NAME FM_ADR_TRIGGER_N
J 0
(300 710);
DISPLAY 0.851064 (300 710);
PAINT WHITE (300 710);
WIRE 16 2175 (1450 -400)(2225 -400);
WIRE 16 2175 (2225 -275)(2225 -400);
WIRE 16 2175 (1450 -275)(1450 -400);
WIRE 16 2175 (1450 -275)(2225 -275);
WIRE 16 -1 (175 -50)(1675 -50);
FORCEPROP 0 LAST CDS_PHYS_NET_NAME JTAG_PLD_TDO_R
J 0
(315 0);
PAINT MONO (315 0);
DISPLAY INVISIBLE (315 0);
FORCEPROP 2 LAST SIG_NAME JTAG_PLD_TDO_R
J 0
(300 -40);
DISPLAY 0.851064 (300 -40);
PAINT WHITE (300 -40);
WIRE 16 -1 (-1950 1175)(-3450 1175);
FORCEPROP 0 LAST CDS_PHYS_NET_NAME FM_PFR_DSW_PWROK_N
J 0
(-3310 1225);
PAINT MONO (-3310 1225);
DISPLAY INVISIBLE (-3310 1225);
FORCEPROP 0 LAST SIG_NAME FM_PFR_DSW_PWROK_N
J 0
(-3225 1185);
DISPLAY 0.680851 (-3225 1185);
PAINT WHITE (-3225 1185);
WIRE 16 -1 (-3325 2275)(-3325 2425);
WIRE 16 -1 (-2250 2275)(-3325 2275);
FORCEPROP 2 LAST SIG_NAME FM_DIMM_12V_CPS_SX_N
J 0
(-3135 2285);
DISPLAY 0.808511 (-3135 2285);
PAINT WHITE (-3135 2285);
WIRE 16 -1 (-3325 2150)(-3325 2275);
WIRE 16 -1 (-3375 -2325)(-1625 -2325);
FORCEPROP 0 LAST CDS_PHYS_NET_NAME PWRGD_SYS_PWROK_R
J 0
(-3235 -2275);
PAINT MONO (-3235 -2275);
DISPLAY INVISIBLE (-3235 -2275);
FORCEPROP 2 LAST SIG_NAME PWRGD_SYS_PWROK_R
J 0
(-3235 -2315);
DISPLAY 0.851064 (-3235 -2315);
PAINT WHITE (-3235 -2315);
DOT 1 (2325 -875);
DOT 1 (2325 -1625);
DOT 1 (-1300 -500);
DOT 1 (-1300 -350);
DOT 1 (-2325 -500);
DOT 1 (1225 -1175);
DOT 1 (-975 -2475);
DOT 1 (-3325 2275);
DOT 1 (-1300 1175);
DOT 1 (-1300 875);
DOT 1 (2325 -1825);
DOT 1 (2325 -1725);
DOT 1 (1000 -875);
DOT 1 (1150 -1075);
DOT 1 (1075 -975);
DOT 1 (2325 -975);
DOT 1 (2325 -775);
DOT 1 (2325 -350);
DOT 1 (2325 -475);
DOT 1 (2325 -50);
DOT 1 (2325 700);
DOT 1 (2325 400);
DOT 1 (2325 850);
DOT 1 (-1300 -150);
FORCENOTE
2020624 DEPOP R1494,ADD R1492
(775 -2175) 0;
DISPLAY LEFT (775 -2175);
DISPLAY 1.063830 (775 -2175);
PAINT WHITE (775 -2175);
FORCENOTE
2020518 DEPOP R1660,ADD R4674
(-2550 -1175) 0;
DISPLAY LEFT (-2550 -1175);
DISPLAY 1.063830 (-2550 -1175);
PAINT WHITE (-2550 -1175);
FORCENOTE
20210902 MODIFY FOR GT
(-4400 3075) 0;
DISPLAY LEFT (-4400 3075);
DISPLAY 2.510638 (-4400 3075);
PAINT PINK (-4400 3075);
FORCENOTE
20220504 DEPOP R139
(2375 -400) 0;
DISPLAY LEFT (2375 -400);
DISPLAY 1.063830 (2375 -400);
PAINT WHITE (2375 -400);
QUIT
